G04 ================== begin FILE IDENTIFICATION RECORD ==================*
G04 Layout Name:  DA0T6MTH8C0_t6m_tray_bp_c_brd_103112_274.brd*
G04 Film Name:    top.art*
G04 File Format:  Gerber RS274X*
G04 File Origin:  Cadence Allegro 16.3-S048*
G04 Origin Date:  Tue Nov 26 11:26:40 2013*
G04 *
G04 Layer:  DRAWING FORMAT/TITLE_BLOCK*
G04 Layer:  VIA CLASS/TOP*
G04 Layer:  PIN/TOP*
G04 Layer:  MANUFACTURING/PHOTOPLOT_OUTLINE*
G04 Layer:  ETCH/TOP*
G04 Layer:  DRAWING FORMAT/TITLE_DATA_TOP*
G04 *
G04 Offset:    (0.00 0.00)*
G04 Mirror:    No*
G04 Mode:      Positive*
G04 Rotation:  0*
G04 FullContactRelief:  No*
G04 UndefLineWidth:     6.00*
G04 ================== end FILE IDENTIFICATION RECORD ====================*
%FSLAX25Y25*MOIN*%
%IR0*IPPOS*OFA0.00000B0.00000*MIA0B0*SFA1.00000B1.00000*%
%ADD21C,.02*%
%ADD10C,.03*%
%ADD19C,.04*%
%ADD41C,.051*%
%ADD22C,.042*%
%ADD37C,.061*%
%ADD16C,.043*%
%ADD35C,.053*%
%ADD40C,.036*%
%ADD23C,.054*%
%ADD17C,.063*%
%ADD15R,.032X.197*%
%ADD28C,.046*%
%ADD47C,.092*%
%ADD11C,.066*%
%ADD45R,.051X.051*%
%ADD39C,.049*%
%ADD29C,.085*%
%ADD44R,.036X.036*%
%ADD18R,.063X.063*%
%ADD30R,.046X.046*%
%ADD13R,.066X.066*%
%ADD36O,.02X.08*%
%ADD24R,.02X.018*%
%ADD42C,.12*%
%ADD32R,.018X.02*%
%ADD34R,.04X.071*%
%ADD25C,.213*%
%ADD31R,.028X.032*%
%ADD12C,.142*%
%ADD48R,.015X.073*%
%ADD27R,.054X.044*%
%ADD50R,.103X.189*%
%ADD38O,.038X.063*%
%ADD33R,.044X.054*%
%ADD43C,.128*%
%ADD26C,.228*%
%ADD14C,.138*%
%ADD49R,.036X.084*%
%ADD46C,.139*%
%ADD20R,.373X.248*%
%ADD51C,.014*%
%ADD52C,.0114*%
%ADD53C,.018*%
%ADD54C,.006*%
%ADD55C,.007*%
%ADD56C,.0096*%
%ADD59C,.03004*%
%ADD58C,.05004*%
%ADD67C,.03182*%
%ADD63C,.07304*%
%ADD62C,.06404*%
%ADD69C,.05604*%
%ADD61C,.07604*%
%ADD65C,.1601*%
%ADD64C,.13006*%
%ADD68C,.11704*%
%ADD66C,.16024*%
%ADD57C,.1822*%
%ADD70R,.05604X.05604*%
%ADD60R,.07604X.07604*%
G75*
%LPD*%
G75*
G36*
G01X35467Y18504D02*
G03I-17750J0D01*
G37*
G36*
G01X40400Y6200D02*
X37700Y8900D01*
Y25222D01*
G02X39143Y26119I1000J0D01*
G03Y32937I1684J3409D01*
G02X37700Y33833I-443J896D01*
G01Y36100D01*
X22700Y51100D01*
X11200D01*
X5800Y56500D01*
Y75936D01*
G02X7276Y76815I1000J0D01*
G03Y83501I1812J3343D01*
G02X5800Y84380I-476J879D01*
G01Y87736D01*
G02X7276Y88615I1000J0D01*
G03X11848Y94573I1812J3342D01*
G02X11867Y95967I726J687D01*
G01X12400Y96500D01*
X14786D01*
G02X15286Y96000I0J-500D01*
G01Y88156D01*
X22890D01*
Y96000D01*
G02X23390Y96500I500J0D01*
G01X26600D01*
X34900Y104800D01*
Y130200D01*
X38900Y134200D01*
X41094D01*
X41324Y134070D01*
X41392Y133956D01*
G03X47664I3136J1871D01*
G01X47732Y134070D01*
X47962Y134200D01*
X52188D01*
G02X52688Y133700I0J-500D01*
G01Y132176D01*
X59990D01*
Y133700D01*
G02X60490Y134200I500J0D01*
G01X66900D01*
X67135Y134153D01*
X87179Y114108D01*
X102590D01*
G03X104155Y115539I0J1571D01*
G02X105151Y116448I996J-91D01*
G01X108139D01*
X111649Y112938D01*
X128600D01*
G03X129412Y113164I0J1572D01*
G02X130928Y112308I516J-856D01*
G01Y110100D01*
G03X134072I1572J0D01*
G01Y115195D01*
X129895Y119372D01*
X117969D01*
G02X116970Y120332I0J1000D01*
G03X116511Y121381I-1570J-62D01*
G01X113621Y124272D01*
X109956D01*
G02X108958Y125209I0J1000D01*
G03X107390Y126682I-1568J-98D01*
G01X101663D01*
G02X100666Y127599I-1J1000D01*
G03X99100Y129042I-1566J-128D01*
G01X93242D01*
X67902Y154382D01*
X57699D01*
X48489Y163592D01*
X47500D01*
G02X47000Y164092I0J500D01*
G01Y201000D01*
X49700Y203700D01*
X80936D01*
G02X81436Y203200I0J-500D01*
G01Y178934D01*
X83592D01*
Y203200D01*
G02X84092Y203700I500J0D01*
G01X117400D01*
X120900Y200200D01*
Y161800D01*
X240900Y41800D01*
X276300D01*
X279200Y38900D01*
Y9800D01*
X275600Y6200D01*
X40400D01*
G37*
G36*
G01X1968Y137795D02*
G02X33464I15748J0D01*
G01Y114173D01*
G02X1968I-15748J0D01*
G01Y137795D01*
G37*
G36*
G01X294500Y7800D02*
X287600Y14700D01*
Y45500D01*
X287125Y45975D01*
X286875D01*
X242175D01*
X123650Y164500D01*
Y201950D01*
X124900Y203200D01*
X160926D01*
G02X161426Y202700I0J-500D01*
G01Y178934D01*
X163592D01*
Y202700D01*
G02X164092Y203200I500J0D01*
G01X199800D01*
X201000Y202000D01*
Y176400D01*
X198100Y173500D01*
Y163300D01*
X204400Y157000D01*
X224000D01*
X230600Y163600D01*
Y190100D01*
X238100Y197600D01*
X302559D01*
G02X325867I11654J-10592D01*
G01X372000D01*
X379100Y190500D01*
X379227D01*
G02X379727Y190000I0J-500D01*
G01X441600D01*
X443684Y192084D01*
Y192184D01*
X452300Y200800D01*
X518600D01*
X528872Y190528D01*
X583372D01*
X593300Y180600D01*
Y98100D01*
X588800Y93600D01*
X534400D01*
X507400Y120600D01*
Y153900D01*
X506910Y154390D01*
Y154702D01*
X506598D01*
X504900Y156400D01*
X471100D01*
X461700Y147000D01*
Y118000D01*
X455000Y111300D01*
Y111200D01*
X439300Y95500D01*
X392500D01*
X378900Y109100D01*
Y157003D01*
G02X378868Y157032I320J385D01*
G01X378300Y157600D01*
X360300D01*
X357000Y154300D01*
X349100D01*
X343000Y148200D01*
X336600D01*
X327700Y139300D01*
Y125000D01*
X334200Y118500D01*
X350100D01*
X351600Y117000D01*
Y101500D01*
X352700Y100400D01*
X363500D01*
X365300Y98600D01*
Y94400D01*
X363900Y93000D01*
X342100D01*
X338900Y89800D01*
Y68800D01*
X345700Y62000D01*
Y10300D01*
X343200Y7800D01*
X294500D01*
G37*
G36*
G01X352065Y31562D02*
G03Y43239I-411J5838D01*
G02X351600Y43737I35J499D01*
G01Y61200D01*
X342400Y70400D01*
Y89600D01*
X344100Y91300D01*
X364100D01*
X372700Y82700D01*
Y10300D01*
X368800Y6400D01*
X355900D01*
X351600Y10700D01*
Y31064D01*
G02X352065Y31562I500J-1D01*
G37*
G36*
G01X376600Y153000D02*
Y103200D01*
X374300Y100900D01*
X365100D01*
X363250Y102750D01*
Y106650D01*
X363200Y106700D01*
Y116100D01*
X359900Y119400D01*
Y153500D01*
X361100Y154700D01*
X374900D01*
X376600Y153000D01*
G37*
G36*
G01X418300Y5200D02*
X401800D01*
X401300Y5700D01*
Y10300D01*
X402050Y11050D01*
X410250D01*
X410300Y11100D01*
X418500D01*
X419400Y10200D01*
Y6300D01*
X418300Y5200D01*
G37*
G36*
G01X506744Y88554D02*
X507045Y88855D01*
G03X504355Y91545I-1345J1345D01*
G01X502940Y90130D01*
Y89610D01*
G02X502440Y89110I-500J0D01*
G01X500558D01*
G03X499273Y88610I0J-1901D01*
G01X499056D01*
Y88384D01*
X498973Y88259D01*
G03X498657Y87203I1585J-1050D01*
G02X497657Y86200I-1000J-3D01*
G01X494600D01*
X488550Y92250D01*
X485900D01*
X485325Y91675D01*
Y86625D01*
X484500Y85800D01*
X481100D01*
X480350Y86550D01*
Y93050D01*
X479000Y94400D01*
X471300D01*
X466027Y89127D01*
X465881Y89097D01*
G03X464910Y86660I319J-1539D01*
G01X465000Y86531D01*
Y86300D01*
G02X464500Y85800I-500J0D01*
G01X463600D01*
X462500Y86900D01*
Y110400D01*
X464200Y112100D01*
X511400D01*
X512900Y110600D01*
Y106600D01*
X511800Y105500D01*
Y90013D01*
G02X510805Y89013I-1000J0D01*
G03X510408Y88960I8J-1571D01*
G01X510345Y88944D01*
X509412D01*
Y88160D01*
X509370Y88065D01*
G03X509242Y87442I1443J-621D01*
G01Y86700D01*
G02X508742Y86200I-500J0D01*
G01X507743D01*
G02X506743Y87203I0J1000D01*
G03X506744Y87208I-1828J368D01*
G01Y88554D01*
G37*
G36*
G01X560800Y6700D02*
Y10700D01*
X561500Y11400D01*
X576400D01*
X577800Y10000D01*
Y6500D01*
X577000Y5700D01*
X561800D01*
X560800Y6700D01*
G37*
G36*
G01X608100Y85500D02*
X599000D01*
X596900Y87600D01*
Y172000D01*
X599100Y174200D01*
X611900D01*
X613300Y172800D01*
Y110600D01*
X609200Y106500D01*
Y86600D01*
X608100Y85500D01*
G37*
G36*
G01X630100Y108000D02*
Y86800D01*
X629100Y85800D01*
X623200D01*
X621800Y87200D01*
Y107700D01*
X623400Y109300D01*
X628800D01*
X630100Y108000D01*
G37*
G36*
G01X633870Y132244D02*
Y163244D01*
X632267D01*
Y172044D01*
X633870D01*
Y198386D01*
X799106D01*
Y172044D01*
X800688D01*
Y163244D01*
X799106D01*
Y112944D01*
X800688D01*
Y104244D01*
X799106D01*
Y78386D01*
X771888D01*
Y86693D01*
X788988D01*
X788964Y103544D01*
X786688D01*
Y113744D01*
X788949D01*
X788927Y128644D01*
X787088D01*
Y135944D01*
X788917D01*
X788878Y162644D01*
X786688D01*
Y172544D01*
X788864D01*
Y172644D01*
X788850Y181850D01*
X718988D01*
Y86693D01*
X736788D01*
X737588D01*
Y78444D01*
Y78386D01*
X736788D01*
X697088D01*
Y86693D01*
X713988D01*
Y181850D01*
X644126D01*
X644135Y172644D01*
X646288D01*
Y162744D01*
X644145D01*
Y135844D01*
X645888D01*
Y128644D01*
X644145D01*
Y113544D01*
X646288D01*
Y103644D01*
X644145D01*
Y86693D01*
X661888D01*
X662688D01*
Y78444D01*
Y78386D01*
X661888D01*
X633870D01*
Y104244D01*
X632267D01*
Y113044D01*
X633870D01*
Y132244D01*
G37*
G36*
G01X767913Y42126D02*
G02X799409I15748J0D01*
G01Y18504D01*
G02X767913I-15748J0D01*
G01Y42126D01*
G37*
G36*
G01X1144100Y10400D02*
X1140700Y7000D01*
X1115923D01*
G02X1115117Y8592I0J1000D01*
G03X1118364Y18504I-13502J9911D01*
G01Y42126D01*
G03X1084866I-16749J0D01*
G01X1084865Y18504D01*
G03X1088113Y8592I16750J0D01*
G02X1087307Y7000I-806J-592D01*
G01X806700D01*
X802550Y11150D01*
Y187450D01*
X808504Y193404D01*
G02X810158Y192376I707J-707D01*
G03X809274Y187008I15866J-5370D01*
G01Y163386D01*
G03X842774I16750J0D01*
G01Y187008D01*
G03X839803Y196531I-16750J-1D01*
G02X840625Y198100I822J569D01*
G01X1169691D01*
G02X1170513Y196531I0J-1000D01*
G03X1167542Y187008I13779J-9524D01*
G01Y163386D01*
G03X1201042I16750J0D01*
G01Y187008D01*
G03X1198071Y196531I-16750J-1D01*
G02X1198893Y198100I822J569D01*
G01X1233600D01*
X1245950Y185750D01*
Y162700D01*
X1243050Y159800D01*
X1219100D01*
X1202150Y142850D01*
Y126150D01*
X1206800Y121500D01*
Y95900D01*
X1212000Y90700D01*
X1239100D01*
X1248000Y81800D01*
Y15100D01*
X1239900Y7000D01*
X1204100D01*
X1201400Y9700D01*
Y84600D01*
X1194700Y91300D01*
X1186900D01*
X1152700D01*
X1146600Y85200D01*
X1144100Y82700D01*
Y10400D01*
G37*
G36*
G01X810276Y187008D02*
G02X841772I15748J0D01*
G01Y163386D01*
G02X810276I-15748J0D01*
G01Y187008D01*
G37*
G36*
G01X1085867Y42126D02*
G02X1117363I15748J0D01*
G01Y18504D01*
G02X1085867I-15748J0D01*
G01Y42126D01*
G37*
G36*
G01X1168544Y187008D02*
G02X1200040I15748J0D01*
G01Y163386D01*
G02X1168544I-15748J0D01*
G01Y187008D01*
G37*
G36*
G01X1214200Y92600D02*
X1209600Y97200D01*
Y120750D01*
X1210748Y121898D01*
X1219602D01*
X1221000Y120500D01*
Y101600D01*
X1222500Y100100D01*
X1246800D01*
X1250500Y103800D01*
Y186400D01*
X1255000Y190900D01*
X1314200D01*
X1323200Y199900D01*
X1391000D01*
X1398950Y191950D01*
X1454850D01*
X1461800Y185000D01*
Y98200D01*
X1455700Y92100D01*
X1406700D01*
X1397376Y101424D01*
X1383100Y115700D01*
Y151100D01*
X1378400Y155800D01*
X1340800D01*
X1334100Y149100D01*
Y114300D01*
X1333850Y114050D01*
Y113750D01*
X1312700Y92600D01*
X1214200D01*
G37*
G36*
G01X1245600Y155000D02*
Y102400D01*
X1244600Y101400D01*
X1233900D01*
X1233250Y102050D01*
Y107650D01*
X1233200Y107700D01*
Y120600D01*
X1229700Y124100D01*
Y155200D01*
X1231600Y157100D01*
X1243500D01*
X1245600Y155000D01*
G37*
G36*
G01X1289900Y8400D02*
Y6100D01*
X1288900Y5100D01*
X1270400D01*
X1269300Y6200D01*
Y8700D01*
X1270200Y9600D01*
X1288700D01*
X1289900Y8400D01*
G37*
G36*
G01X1379200Y91000D02*
X1376850Y93350D01*
X1358950D01*
X1358411Y92811D01*
X1358313Y92773D01*
G03X1357600Y89713I687J-1773D01*
G01Y86700D01*
X1356600Y85700D01*
X1354200D01*
X1353500Y86400D01*
Y88650D01*
X1352075Y90075D01*
X1346125D01*
X1343600Y92600D01*
X1343010D01*
X1342909Y92702D01*
X1340400D01*
G03X1338585Y91366I0J-1901D01*
G01X1338548Y91248D01*
X1335800Y88500D01*
Y87543D01*
X1332932Y84675D01*
G02X1332225I-353J354D01*
G01X1331900Y85000D01*
Y106000D01*
X1333400Y107500D01*
X1380400D01*
X1382300Y105600D01*
Y89244D01*
G02X1381800Y88744I-500J0D01*
G01X1381481D01*
X1381418Y88760D01*
G03X1380608I-405J-1518D01*
G01X1380545Y88744D01*
X1379700D01*
G02X1379200Y89244I0J500D01*
G01Y91000D01*
G37*
G36*
G01X1433000Y6400D02*
X1432000Y7400D01*
Y11300D01*
X1432574Y11874D01*
X1437900D01*
G03X1438509Y11974I1J1901D01*
G01X1438587Y12000D01*
X1442281D01*
X1442318Y11994D01*
G03X1442600Y11974I275J1881D01*
G01X1447726D01*
X1448500Y11200D01*
Y7600D01*
X1447300Y6400D01*
X1433000D01*
G37*
G36*
G01X1479000Y89600D02*
X1477700Y88300D01*
X1467200D01*
X1465100Y90400D01*
Y173000D01*
X1467700Y175600D01*
X1481600D01*
X1483400Y173800D01*
Y115000D01*
X1479000Y110600D01*
Y89600D01*
G37*
G36*
G01X1499800Y111900D02*
Y89400D01*
X1498500Y88100D01*
X1492900D01*
X1490700Y90300D01*
Y112100D01*
X1491900Y113300D01*
X1498400D01*
X1499800Y111900D01*
G37*
G36*
G01X1503949Y132244D02*
Y163244D01*
X1502346D01*
Y172044D01*
X1503949D01*
Y198386D01*
X1669185D01*
Y172044D01*
X1670767D01*
Y163244D01*
X1669185D01*
Y112944D01*
X1670767D01*
Y104244D01*
X1669185D01*
Y78386D01*
X1641967D01*
Y86693D01*
X1659067D01*
X1659043Y103544D01*
X1656767D01*
Y113744D01*
X1659028D01*
X1659006Y128644D01*
X1657167D01*
Y135944D01*
X1658996D01*
X1658957Y162644D01*
X1656767D01*
Y172544D01*
X1658943D01*
Y172644D01*
X1658929Y181850D01*
X1589067D01*
Y86693D01*
X1606867D01*
X1607667D01*
Y78444D01*
Y78386D01*
X1606867D01*
X1567167D01*
Y86693D01*
X1584067D01*
Y181850D01*
X1514205D01*
X1514214Y172644D01*
X1516367D01*
Y162744D01*
X1514224D01*
Y135844D01*
X1515967D01*
Y128644D01*
X1514224D01*
Y113544D01*
X1516367D01*
Y103644D01*
X1514224D01*
Y86693D01*
X1531967D01*
X1532767D01*
Y78444D01*
Y78386D01*
X1531967D01*
X1503949D01*
Y104244D01*
X1502346D01*
Y113044D01*
X1503949D01*
Y132244D01*
G37*
G36*
G01X1688262Y18504D02*
G03I-17750J0D01*
G37*
G36*
G01X1678000Y117200D02*
Y78900D01*
X1676400Y77300D01*
X1673200D01*
X1671900Y78600D01*
Y116500D01*
X1673600Y118200D01*
X1677000D01*
X1678000Y117200D01*
G37*
%LPC*%
G75*
G36*
G01X85652Y69147D02*
G03X85124Y68681I-29J-499D01*
G02X81712Y72093I-3195J217D01*
G03X82177Y72620I-34J499D01*
G02X82178Y73049I3689J206D01*
G03X81712Y73577I-499J29D01*
G02X85124Y76988I217J3195D01*
G03X85652Y76523I499J34D01*
G02X86080I214J-3688D01*
G03X86608Y76988I29J499D01*
G02X90020Y73577I3195J-216D01*
G03X89554Y73049I33J-499D01*
G02X89560Y72835I-3688J-210D01*
G02X89554Y72620I-3694J-4D01*
G03X90020Y72093I499J-28D01*
G02X92946Y68288I-217J-3195D01*
G01X92923Y68166D01*
X92996Y67928D01*
X93389Y67534D01*
X101739D01*
G02X102296Y67432I0J-1572D01*
G01X102382Y67400D01*
X103000D01*
X104900Y69300D01*
Y77400D01*
X105500Y78000D01*
X123500D01*
X126100Y75400D01*
Y63016D01*
X126102Y63015D01*
Y57185D01*
X124415Y55498D01*
X100785D01*
X99198Y57085D01*
Y63415D01*
X99322Y63538D01*
G03X98968Y64391I-354J353D01*
G01X92087D01*
X90773Y65705D01*
X90535Y65778D01*
X90413Y65755D01*
G02X86608Y68681I-610J3143D01*
G03X86080Y69147I-499J-33D01*
G02X85652I-214J3688D01*
G37*
G36*
G01Y100643D02*
G03X85124Y100177I-29J-499D01*
G02X81712Y103589I-3195J217D01*
G03X82177Y104116I-34J499D01*
G02X82178Y104545I3689J206D01*
G03X81712Y105073I-499J29D01*
G02X85124Y108484I217J3195D01*
G03X85652Y108019I499J34D01*
G02X86080I214J-3688D01*
G03X86608Y108484I29J499D01*
G02X90020Y105073I3195J-216D01*
G03X89554Y104545I33J-499D01*
G02X89560Y104331I-3688J-210D01*
G02X89554Y104116I-3694J-4D01*
G03X90020Y103589I499J-28D01*
G02X86608Y100177I-217J-3195D01*
G03X86080Y100643I-499J-33D01*
G02X85652I-214J3688D01*
G37*
G36*
G01X8214Y127758D02*
G02X27218I9502J10037D01*
G03X26616Y126359I1325J-1399D01*
G01Y114173D01*
G02X8816I-8900J0D01*
G01Y126359D01*
G03X8214Y127758I-1927J0D01*
G37*
G36*
G01X323106Y163386D02*
G02X305320I-8893J0D01*
G01Y175572D01*
G03X304716Y176977I-1934J1D01*
G02X303686Y195952I9497J10031D01*
G03X303759Y196049I-761J649D01*
G02X324667I10454J-9041D01*
G03X324740Y195952I834J552D01*
G02X323710Y176977I-10527J-8944D01*
G03X323105Y175572I1330J-1405D01*
G01X323106Y163386D01*
G37*
G36*
G01X774159Y32089D02*
G02X793163I9502J10037D01*
G03X792561Y30690I1325J-1399D01*
G01Y18504D01*
G02X774761I-8900J0D01*
G01Y30690D01*
G03X774159Y32089I-1927J0D01*
G37*
G36*
G01X816522Y176971D02*
G02X835526I9502J10037D01*
G03X834924Y175572I1325J-1399D01*
G01Y163386D01*
G02X817124I-8900J0D01*
G01Y175572D01*
G03X816522Y176971I-1927J0D01*
G37*
G36*
G01X1092113Y32089D02*
G02X1111117I9502J10037D01*
G03X1110515Y30690I1325J-1399D01*
G01Y18504D01*
G02X1092715I-8900J0D01*
G01Y30690D01*
G03X1092113Y32089I-1927J0D01*
G37*
G36*
G01X1174790Y176971D02*
G02X1193794I9502J10037D01*
G03X1193192Y175572I1325J-1399D01*
G01Y163386D01*
G02X1175392I-8900J0D01*
G01Y175572D01*
G03X1174790Y176971I-1927J0D01*
G37*
G54D59*
X125000Y126400D03*
X111500Y129900D03*
X119700Y132400D03*
X114300Y134900D03*
X108900Y137300D03*
X119800Y124390D03*
G54D58*
X270300Y20200D03*
X240300D03*
X227100Y43000D03*
X209400Y60900D03*
X213100Y49600D03*
X210300Y20200D03*
X174200Y96300D03*
X175000Y62300D03*
X191700Y75400D03*
X183100Y49600D03*
X180300Y20200D03*
X148800Y85000D03*
X153100Y49600D03*
X166500Y34700D03*
X150300Y20200D03*
X143000Y105700D03*
X144200Y96300D03*
X133100Y71300D03*
X144500Y40000D03*
X143800Y53600D03*
X143300Y27300D03*
X123100Y49600D03*
X350200Y181100D03*
X281000Y180700D03*
X252800Y179900D03*
X350000Y161800D03*
X280000Y159800D03*
X252200Y159400D03*
X267700Y145200D03*
X300300Y140000D03*
X307800Y101100D03*
X281800Y100900D03*
X216400Y100500D03*
X251600Y100100D03*
X273300Y94900D03*
X254400Y74300D03*
X283600Y69500D03*
X257800Y51200D03*
X806800Y26700D03*
X810700Y65200D03*
X836800Y26700D03*
X825200Y111700D03*
X840700Y65200D03*
X855200Y111700D03*
X855400Y173000D03*
X866800Y26700D03*
X870700Y65200D03*
X896800Y26700D03*
X900700Y65200D03*
X885200Y111700D03*
X885400Y173000D03*
X926800Y26700D03*
X915200Y111700D03*
X915400Y173000D03*
X930700Y65200D03*
X945200Y111700D03*
X945400Y173000D03*
X956800Y26700D03*
X960700Y65200D03*
X975200Y111700D03*
X975400Y173000D03*
X986800Y26700D03*
X990700Y65200D03*
X1018800Y26300D03*
X1005200Y111700D03*
X1005400Y173000D03*
X1022700Y64800D03*
X1037200Y111300D03*
X1035400Y173000D03*
X1048800Y26300D03*
X1052700Y64800D03*
X1067200Y111300D03*
X1067400Y172600D03*
X1078800Y26300D03*
X1082700Y64800D03*
X1097200Y111300D03*
X1097400Y172600D03*
X1136600Y19700D03*
X1135400Y41000D03*
X1127200Y111300D03*
X1127400Y172600D03*
X1157400D03*
G54D67*
X526612Y142000D03*
G54D63*
X56339Y124016D03*
Y112205D03*
Y100394D03*
Y88583D03*
Y76772D03*
Y64961D03*
Y53150D03*
Y41339D03*
G54D62*
X89803Y84646D03*
Y92520D03*
X81929Y84646D03*
Y92520D03*
G54D69*
X1205984Y11810D03*
Y19684D03*
Y27558D03*
Y43306D03*
Y51180D03*
X1213858Y11810D03*
Y19684D03*
Y27558D03*
Y43306D03*
Y51180D03*
Y59054D03*
G54D61*
X109288Y103958D03*
Y92458D03*
G54D65*
X508859Y176650D03*
X1378938D03*
G54D64*
X109400Y41000D03*
X1009700Y81500D03*
G54D68*
X1221732Y37400D03*
G54D66*
X463859Y176650D03*
X1333938D03*
G54D57*
X17717Y18504D03*
X1670512D03*
G54D70*
X1205984Y59054D03*
G54D60*
X119288Y103958D03*
Y92458D03*
X19088Y80158D03*
%LPD*%
G75*
G36*
G01X125100Y62600D02*
Y57600D01*
X124000Y56500D01*
X105000D01*
X101200D01*
X100200Y57500D01*
Y63000D01*
X100800Y63600D01*
X105300D01*
X124100D01*
X125100Y62600D01*
G37*
G54D10*
G01X490276Y52362D02*
Y54876D01*
X492100Y56700D01*
Y90500D01*
G01D02*
X488800Y93800D01*
G01X1358600Y73700D02*
X1361800Y70500D01*
Y66745D01*
X1360355Y65300D01*
Y52362D01*
X8221Y28000D03*
Y9008D03*
X4287Y18504D03*
X17717Y5074D03*
X27213Y28000D03*
X31147Y18504D03*
X27213Y9008D03*
X17717Y31934D03*
X477630Y78800D03*
X487558Y78600D03*
X471787Y78400D03*
X496242Y78600D03*
X504842Y78684D03*
X702610Y53111D03*
X713900Y60500D03*
X707600Y57900D03*
X1341187Y78400D03*
X1348300Y78500D03*
X1357700Y78700D03*
X1364258D03*
X1376358D03*
X1572300Y53500D03*
X1579300Y57900D03*
X1586100Y60500D03*
X1661016Y28000D03*
Y9008D03*
X1657082Y18504D03*
X1670512Y5074D03*
X1680008Y28000D03*
X1683942Y18504D03*
X1680008Y9008D03*
X1670512Y31934D03*
G54D20*
X62521Y191536D03*
X102521D03*
X142521D03*
X182521D03*
G54D11*
X9088Y80158D03*
Y91958D03*
X109288Y92458D03*
Y103958D03*
G54D12*
X17717Y18504D03*
X1670512D03*
G54D30*
X335906Y59054D03*
X1205984D03*
G54D21*
G01X354460Y121642D02*
X350700D01*
G01X332000Y128960D02*
X339318Y121642D01*
X350700D01*
G01X340473Y129060D02*
X344433Y125100D01*
X345900D01*
G01D02*
X349418D01*
X354460Y130142D01*
G01X332000Y136440D02*
X337660Y142100D01*
X345700D01*
X347350Y143750D01*
G01X351992Y149118D02*
Y148392D01*
X347350Y143750D01*
G01X346906Y137693D02*
X348495Y139282D01*
X352092D01*
G01X340473Y136540D02*
X345753D01*
X346906Y137693D01*
G01X622658Y112158D02*
X626173Y115673D01*
Y131360D01*
G01X618140Y112158D02*
X622658D01*
G01X618140Y120258D02*
X622200D01*
G01X618140D02*
Y126009D01*
X617949Y126200D01*
Y131360D01*
G01X626173Y148400D02*
Y138840D01*
G01X617949D02*
Y147000D01*
G01X622013Y158618D02*
X626173Y154458D01*
Y148400D01*
G01X617949Y147000D02*
X619931Y148982D01*
X621908D01*
G01X1219600Y129400D02*
Y131600D01*
X1222542Y134542D01*
X1225160D01*
G01X1214100Y128860D02*
X1217300D01*
X1217840Y129400D01*
X1219600D01*
G01X1219400Y123900D02*
X1210860D01*
X1206000Y128760D01*
G01X1219400Y123900D02*
X1221742Y126242D01*
X1225160D01*
G01X1211200Y144900D02*
X1206000Y139700D01*
Y136240D01*
G01X1211200Y144900D02*
X1219905Y153605D01*
X1222304D01*
G01X1217405Y143895D02*
X1214100Y140590D01*
Y136340D01*
G01X1217405Y143895D02*
X1222199D01*
G01X1488240Y117558D02*
X1492300D01*
G01X1495800Y135760D02*
Y121058D01*
X1492300Y117558D01*
G01X1495800Y143240D02*
Y147800D01*
G01X1488240Y126358D02*
X1492042D01*
G01X1488240D02*
Y130560D01*
X1487600Y131200D01*
Y135760D01*
G01Y143240D02*
Y147000D01*
G01X1495800Y147800D02*
Y158616D01*
X1492125Y162291D01*
G01X1487600Y147000D02*
Y147989D01*
X1492211Y152600D01*
X64500Y165200D03*
X99100Y127470D03*
X89400Y165300D03*
X120500Y59400D03*
X114400Y59700D03*
X107500Y59500D03*
X102400Y59600D03*
X111958Y73600D03*
X121958Y70900D03*
X116958Y68600D03*
X106958Y68500D03*
X122758Y82442D03*
X117158Y82542D03*
X112158Y82342D03*
X106958Y82142D03*
X102590Y115680D03*
X115400Y120270D03*
X107390Y125110D03*
X119800Y124390D03*
X108900Y137300D03*
X114300Y134900D03*
X119700Y132400D03*
X111500Y129900D03*
X105800Y165400D03*
X125558Y79642D03*
X128600Y114510D03*
X132500Y110100D03*
X125000Y126400D03*
X141400Y164800D03*
X129000D03*
X169200Y165200D03*
X155500Y164800D03*
X183300Y164700D03*
X346800Y113500D03*
X345400Y107600D03*
X346200Y102500D03*
X350700Y121642D03*
X345900Y125100D03*
X347350Y143750D03*
X346906Y137693D03*
X362500Y97100D03*
X357600Y97000D03*
X357800Y114657D03*
X357600Y108561D03*
X356861Y102961D03*
X367200Y124000D03*
X397800Y23600D03*
Y19500D03*
X398307Y35000D03*
Y46100D03*
X396732Y78932D03*
X417900Y6700D03*
X414900Y6500D03*
X410200Y6700D03*
X404400Y6800D03*
X408200Y23500D03*
Y19900D03*
X405531Y21960D03*
X400531D03*
X400100Y13900D03*
X412800Y16200D03*
X417205Y35000D03*
X407600D03*
X407756Y46100D03*
X417205D03*
X410906D03*
X414055Y46200D03*
X412480Y80900D03*
X403032Y89532D03*
X415630Y80700D03*
X412300Y85600D03*
X421929Y78400D03*
X409331Y88600D03*
X406181Y82300D03*
X399882Y79318D03*
X426500Y35000D03*
X426654Y46100D03*
X426200Y78100D03*
X446000Y38400D03*
Y33900D03*
X455400Y34000D03*
Y38600D03*
X447880Y36200D03*
X453480D03*
X465600Y55900D03*
X463435Y79865D03*
X453900Y92300D03*
X466200Y87558D03*
X453300Y86800D03*
X451100Y81400D03*
X452100Y97000D03*
X466100Y83258D03*
X452000Y102200D03*
X466300Y100900D03*
X474500Y3900D03*
X490200Y4000D03*
X488800Y73700D03*
X488000Y89800D03*
X477630Y88900D03*
X488800Y93800D03*
X507200Y4200D03*
X505700Y90200D03*
X511600Y108000D03*
X520900Y22500D03*
X525600Y22600D03*
Y13900D03*
X520800Y13800D03*
X523300Y15580D03*
Y20580D03*
X525700Y99300D03*
X519400Y96400D03*
X520439Y91000D03*
X516500Y87442D03*
X526612Y142000D03*
X559425Y13575D03*
X560198Y46100D03*
X556900Y35000D03*
X547599D03*
X557048Y46100D03*
X547599D03*
X558623Y79200D03*
X552324Y78500D03*
X546024Y79200D03*
X549174Y89400D03*
X575600Y7600D03*
X571500Y7500D03*
X567500Y7300D03*
X563100Y7200D03*
X582416Y16466D03*
X567100Y20500D03*
X575900Y20800D03*
X575800Y24300D03*
X567000Y24400D03*
X573721Y22500D03*
X568721D03*
X563347Y46100D03*
X575946D03*
X566497D03*
X575800Y35000D03*
X566497D03*
X571221Y79700D03*
X568072Y81500D03*
X564922Y81900D03*
X561772Y80800D03*
X574371Y78400D03*
X563800Y87700D03*
X604400Y96000D03*
X604200Y107400D03*
X614900Y90157D03*
X615600Y95139D03*
X626100Y99900D03*
X625600Y95400D03*
X625700Y90100D03*
X615500Y100157D03*
X622658Y112158D03*
X622200Y120258D03*
X626600Y106100D03*
X615500Y105157D03*
X626173Y148400D03*
X617949Y147000D03*
X648300Y55600D03*
X651500Y94700D03*
X651100Y91100D03*
X655200Y4100D03*
X661600Y75900D03*
X667200Y75700D03*
X665100Y55900D03*
X659310Y72900D03*
X664310D03*
X654400Y92100D03*
Y97100D03*
X670414Y96486D03*
X672638Y93290D03*
X666614Y121000D03*
X661614D03*
X658400Y102500D03*
X659390Y117490D03*
X668839Y117661D03*
X671063Y125930D03*
X676063D03*
X667500Y126200D03*
X688800Y4100D03*
X680300Y75600D03*
X681600Y55500D03*
X698400Y90300D03*
X689723Y89400D03*
X689311Y96311D03*
X679862Y96538D03*
X677638Y93290D03*
X678288Y122700D03*
X697185Y117385D03*
X687736Y118700D03*
X689961Y122030D03*
X694961D03*
X685600Y133200D03*
X680900D03*
X680612Y129600D03*
X685612D03*
X701100Y16900D03*
X701670Y97100D03*
Y92100D03*
X701732Y101968D03*
X740300Y87300D03*
X735807Y96593D03*
X745256Y96044D03*
X724400Y105600D03*
X729400D03*
X730310Y115390D03*
X725310D03*
X743681Y117400D03*
X731950Y111850D03*
X723500Y118900D03*
X722400Y102300D03*
X730900Y108900D03*
X753100Y75100D03*
X765600Y74800D03*
X761929Y72900D03*
X756929D03*
X752480Y92830D03*
X747480D03*
X764153Y96153D03*
X754704Y96196D03*
X745905Y120452D03*
X750905D03*
X762578Y117300D03*
X753130D03*
X754300Y121400D03*
X764803Y120330D03*
X764000Y124700D03*
X760410Y124730D03*
X755410D03*
X774600Y90300D03*
X778200Y92130D03*
Y97130D03*
X776032Y101968D03*
X772027Y117300D03*
X769803Y120330D03*
X1223200Y99000D03*
X1218000Y99100D03*
X1216500Y119500D03*
X1216700Y114400D03*
X1216500Y108300D03*
X1216400Y102600D03*
X1226900Y119561D03*
Y114043D03*
X1227000Y108361D03*
X1227100Y102861D03*
X1219600Y129400D03*
X1219400Y123900D03*
X1211200Y144900D03*
X1217405Y143895D03*
X1229800Y96400D03*
X1238900Y123300D03*
X1238100Y127900D03*
X1273000Y6100D03*
X1270610Y21960D03*
X1267700Y22900D03*
Y19700D03*
X1268700Y14000D03*
X1268386Y35000D03*
Y46100D03*
X1266811Y78300D03*
X1273111Y89100D03*
X1269961Y78400D03*
X1276700Y5900D03*
X1280900D03*
X1285800D03*
X1278700Y19800D03*
Y23000D03*
X1275610Y21960D03*
X1289775Y11975D03*
X1296600Y35000D03*
X1277700D03*
X1287284D03*
X1296733Y46100D03*
X1287284D03*
X1277835D03*
X1284134D03*
X1280985Y46200D03*
X1295158Y79158D03*
X1292008Y80192D03*
X1288859Y78400D03*
X1279410Y87200D03*
X1285709Y84300D03*
X1276260Y79000D03*
X1282559Y85700D03*
X1315879Y38200D03*
X1315979Y33900D03*
X1317959Y36200D03*
X1323559D03*
X1325279Y38600D03*
Y33800D03*
X1335300Y55600D03*
X1340400Y90800D03*
X1333400Y82900D03*
X1323000Y99239D03*
X1321400Y92800D03*
X1329500Y81400D03*
X1321500Y82600D03*
X1322500Y87800D03*
X1335600Y96500D03*
X1360600Y4000D03*
X1344700Y4100D03*
X1358200Y69000D03*
X1358600Y73700D03*
X1359000Y91000D03*
X1345100Y105500D03*
X1376300Y4000D03*
X1371600Y86463D03*
X1387400Y87242D03*
X1389900Y97600D03*
X1371600Y96000D03*
X1395679Y22600D03*
X1390979Y22500D03*
X1390879Y13800D03*
X1395679Y13900D03*
X1393379Y20580D03*
Y15580D03*
X1395200Y99500D03*
X1391000Y92400D03*
X1433700Y8000D03*
X1429525Y13775D03*
X1417678Y46100D03*
X1427127D03*
X1417678Y35000D03*
X1427000D03*
X1433426Y46100D03*
X1430277D03*
X1416103Y78400D03*
X1422403D03*
X1434200Y88100D03*
X1435001Y81700D03*
X1431851Y80200D03*
X1428702Y79002D03*
X1429400Y88500D03*
X1442400Y8200D03*
X1438000Y8100D03*
X1446300Y8300D03*
X1436500Y23900D03*
Y20700D03*
X1445900Y20800D03*
X1445700Y24400D03*
X1443800Y22500D03*
X1438800D03*
X1454600Y17600D03*
X1446025Y46100D03*
X1436576D03*
X1445900Y35000D03*
X1436576D03*
X1444450Y78300D03*
X1441300Y79100D03*
X1438151Y81100D03*
X1472400Y102700D03*
X1474200Y106600D03*
X1494200Y97800D03*
X1495000Y92800D03*
X1484700Y93057D03*
X1485000Y98057D03*
X1494700Y111200D03*
X1494500Y102700D03*
X1484900Y103257D03*
X1492300Y117558D03*
X1484800Y109357D03*
X1492042Y126358D03*
X1495800Y147800D03*
X1487600Y147000D03*
X1527200Y3800D03*
X1518200Y55600D03*
X1524478Y97100D03*
Y92100D03*
X1521579Y94700D03*
X1521179Y91100D03*
X1534388Y72900D03*
X1529388D03*
X1550500Y75500D03*
X1537279Y75700D03*
X1531679Y75900D03*
X1535300Y55800D03*
X1542716Y93290D03*
X1547716D03*
X1549940Y96538D03*
X1540492Y96486D03*
X1531692Y121000D03*
X1528478Y102500D03*
X1548366Y122700D03*
X1538917Y117661D03*
X1529468Y117490D03*
X1536692Y121000D03*
X1546141Y125930D03*
X1550690Y129600D03*
X1550979Y133200D03*
X1537579Y126200D03*
X1541141Y125930D03*
X1559000Y4200D03*
X1570800Y18900D03*
X1551800Y55700D03*
X1571748Y92100D03*
Y97100D03*
X1559802Y89400D03*
X1559389Y96311D03*
X1568479Y90300D03*
X1571810Y101968D03*
X1557814Y118700D03*
X1567263Y117385D03*
X1565039Y122030D03*
X1560039D03*
X1555690Y129600D03*
X1555679Y133200D03*
X1594478Y105600D03*
X1592900Y101700D03*
X1593300Y119000D03*
X1595388Y115390D03*
X1617558Y92830D03*
X1610379Y87300D03*
X1605885Y96593D03*
X1615334Y96044D03*
X1599478Y105600D03*
X1600388Y115390D03*
X1613759Y117400D03*
X1602028Y111850D03*
X1600900Y108700D03*
X1615983Y120452D03*
X1635679Y74800D03*
X1623179Y75100D03*
X1627007Y72900D03*
X1632007D03*
X1622558Y92830D03*
X1624782Y96196D03*
X1634231Y96153D03*
X1620983Y120452D03*
X1639881Y120330D03*
X1623208Y117300D03*
X1642105D03*
X1632656D03*
X1624300Y121500D03*
X1634881Y120330D03*
X1625488Y124730D03*
X1630488D03*
X1634179Y124300D03*
X1648278Y97130D03*
X1644679Y90300D03*
X1648278Y92130D03*
X1646110Y101968D03*
X1676100Y78900D03*
G54D31*
X346524Y90099D03*
Y95899D03*
X352424Y90099D03*
Y95899D03*
X1217324Y89699D03*
Y95499D03*
X1223424D03*
Y89699D03*
G54D13*
X19088Y80158D03*
Y91958D03*
X119288Y92458D03*
Y103958D03*
G54D40*
X466654Y7874D03*
Y29922D03*
Y24410D03*
Y18898D03*
Y13386D03*
Y51969D03*
Y46457D03*
Y40945D03*
Y35433D03*
X474528Y8268D03*
X482402Y7874D03*
X490276Y8268D03*
X474528Y30315D03*
X482402Y29922D03*
X490276Y30315D03*
X474528Y24803D03*
X482402Y24410D03*
X490276Y24803D03*
X474528Y19292D03*
X482402Y18898D03*
X490276Y19292D03*
X474528Y13780D03*
X482402Y13386D03*
X490276Y13780D03*
X474528Y52362D03*
X482402Y51969D03*
X490276Y52362D03*
X474528Y46851D03*
X482402Y46457D03*
X490276Y46851D03*
X474528Y41339D03*
X482402Y40945D03*
X490276Y41339D03*
X474528Y35827D03*
X482402Y35433D03*
X490276Y35827D03*
X498150Y7874D03*
Y29922D03*
X506024Y30315D03*
X498150Y24410D03*
X506024Y24803D03*
X498150Y18898D03*
X506024Y19292D03*
X498150Y13386D03*
X506024Y13780D03*
X498150Y51969D03*
X506024Y52362D03*
X498150Y46457D03*
X506024Y46851D03*
X498150Y40945D03*
X506024Y41339D03*
X498150Y35433D03*
X506024Y35827D03*
X649173Y7874D03*
Y29922D03*
Y24410D03*
Y18898D03*
Y13386D03*
Y51969D03*
Y46457D03*
Y40945D03*
Y35433D03*
X657047Y8268D03*
X664921Y7874D03*
X672795Y8268D03*
X657047Y30315D03*
X664921Y29922D03*
X672795Y30315D03*
X657047Y24803D03*
X664921Y24410D03*
X672795Y24803D03*
X657047Y19292D03*
X664921Y18898D03*
X672795Y19292D03*
X657047Y13780D03*
X664921Y13386D03*
X672795Y13780D03*
X657047Y52362D03*
X664921Y51969D03*
X672795Y52362D03*
X657047Y46851D03*
X664921Y46457D03*
X672795Y46851D03*
X657047Y41339D03*
X664921Y40945D03*
X672795Y41339D03*
X657047Y35827D03*
X664921Y35433D03*
X672795Y35827D03*
X680669Y7874D03*
Y29922D03*
X688543Y30315D03*
X680669Y24410D03*
X688543Y24803D03*
X680669Y18898D03*
X688543Y19292D03*
X680669Y13386D03*
X688543Y13780D03*
X680669Y51969D03*
X688543Y52362D03*
X680669Y46457D03*
X688543Y46851D03*
X680669Y40945D03*
X688543Y41339D03*
X680669Y35433D03*
X688543Y35827D03*
X1336733Y7874D03*
X1344607Y8268D03*
X1336733Y29922D03*
X1344607Y30315D03*
X1336733Y24410D03*
X1344607Y24803D03*
X1336733Y18898D03*
X1344607Y19292D03*
X1336733Y13386D03*
X1344607Y13780D03*
X1336733Y51969D03*
X1344607Y52362D03*
X1336733Y46457D03*
X1344607Y46851D03*
X1336733Y40945D03*
X1344607Y41339D03*
X1336733Y35433D03*
X1344607Y35827D03*
X1352481Y7874D03*
X1360355Y8268D03*
X1352481Y29922D03*
X1360355Y30315D03*
X1352481Y24410D03*
X1360355Y24803D03*
X1352481Y18898D03*
X1360355Y19292D03*
X1352481Y13386D03*
X1360355Y13780D03*
X1352481Y51969D03*
X1360355Y52362D03*
X1352481Y46457D03*
X1360355Y46851D03*
X1352481Y40945D03*
X1360355Y41339D03*
X1352481Y35433D03*
X1360355Y35827D03*
X1368229Y7874D03*
Y29922D03*
X1376103Y30315D03*
X1368229Y24410D03*
X1376103Y24803D03*
X1368229Y18898D03*
X1376103Y19292D03*
X1368229Y13386D03*
X1376103Y13780D03*
X1368229Y51969D03*
X1376103Y52362D03*
X1368229Y46457D03*
X1376103Y46851D03*
X1368229Y40945D03*
X1376103Y41339D03*
X1368229Y35433D03*
X1376103Y35827D03*
X1519252Y7874D03*
X1527126Y8268D03*
X1519252Y29922D03*
X1527126Y30315D03*
X1519252Y24410D03*
X1527126Y24803D03*
X1519252Y18898D03*
X1527126Y19292D03*
X1519252Y13386D03*
X1527126Y13780D03*
X1519252Y51969D03*
X1527126Y52362D03*
X1519252Y46457D03*
X1527126Y46851D03*
X1519252Y40945D03*
X1527126Y41339D03*
X1519252Y35433D03*
X1527126Y35827D03*
X1535000Y7874D03*
X1542874Y8268D03*
X1550748Y7874D03*
X1535000Y29922D03*
X1542874Y30315D03*
X1550748Y29922D03*
X1535000Y24410D03*
X1542874Y24803D03*
X1550748Y24410D03*
X1535000Y18898D03*
X1542874Y19292D03*
X1550748Y18898D03*
X1535000Y13386D03*
X1542874Y13780D03*
X1550748Y13386D03*
X1535000Y51969D03*
X1542874Y52362D03*
X1550748Y51969D03*
X1535000Y46457D03*
X1542874Y46851D03*
X1550748Y46457D03*
X1535000Y40945D03*
X1542874Y41339D03*
X1550748Y40945D03*
X1535000Y35433D03*
X1542874Y35827D03*
X1550748Y35433D03*
X1558622Y30315D03*
Y24803D03*
Y19292D03*
Y13780D03*
Y52362D03*
Y46851D03*
Y41339D03*
Y35827D03*
G54D22*
X85866Y72835D03*
Y104331D03*
G54D14*
X17716Y114173D03*
X314213Y163386D03*
X783661Y18504D03*
X826024Y163386D03*
X1101615Y18504D03*
X1184292Y163386D03*
G54D50*
X1676417Y114567D03*
G54D32*
X350465Y108561D03*
Y102961D03*
Y114657D03*
X361285Y102961D03*
X364435D03*
X361285Y114657D03*
X364435D03*
X361285Y108561D03*
X364435D03*
X353615D03*
Y102961D03*
Y114657D03*
X460285Y87315D03*
X463435D03*
X460285Y91615D03*
X463435D03*
X460285Y95915D03*
X463435D03*
X460285Y83015D03*
X463435D03*
X460285Y104515D03*
X463435D03*
X460285Y100215D03*
X463435D03*
X474692Y91958D03*
X477842D03*
X471787Y87558D03*
X468637D03*
X471787Y83258D03*
X468637D03*
X513787Y91561D03*
X510637D03*
X513787Y95861D03*
X510637D03*
X510813Y83242D03*
X513963D03*
X510813Y87442D03*
X513963D03*
X513787Y104461D03*
X510637D03*
X513787Y100161D03*
X510637D03*
X611415Y95139D03*
X608265D03*
X611415Y90157D03*
X608265D03*
X619613D03*
X622763D03*
X619613Y95139D03*
X622763D03*
X611415Y105157D03*
X608265D03*
X611415Y100157D03*
X608265D03*
X619613D03*
X622763D03*
X619613Y105157D03*
X622763D03*
X1223263Y108361D03*
X1220113D03*
X1223263Y102861D03*
X1220113D03*
X1223263Y119561D03*
X1220113D03*
X1223263Y114043D03*
X1220113D03*
X1230985Y119561D03*
X1234135D03*
X1230985Y114043D03*
X1234135D03*
X1230985Y108361D03*
X1234135D03*
X1230985Y102861D03*
X1234135D03*
X1329637Y85839D03*
X1332787D03*
X1329637Y90339D03*
X1332787D03*
X1329637Y94639D03*
X1332787D03*
X1329737Y99239D03*
X1332887D03*
X1341187Y83258D03*
X1338037D03*
X1341187Y87558D03*
X1338037D03*
X1384287Y95861D03*
X1381137D03*
X1384163Y91561D03*
X1381013D03*
Y83042D03*
X1384163D03*
X1381013Y87242D03*
X1384163D03*
X1384287Y104461D03*
X1381137D03*
X1384287Y100161D03*
X1381137D03*
X1481215Y93057D03*
X1478065D03*
X1481215Y98057D03*
X1478065D03*
X1481215Y103257D03*
X1478065D03*
X1481215Y109357D03*
X1478065D03*
X1488313Y93057D03*
X1491463D03*
X1488313Y98057D03*
X1491463D03*
X1488313Y103257D03*
X1491463D03*
X1488313Y109357D03*
X1491463D03*
G54D23*
X81929Y76772D03*
Y68898D03*
X89803Y76772D03*
Y68898D03*
X81929Y100394D03*
Y92520D03*
Y84646D03*
X89803Y100394D03*
Y92520D03*
Y84646D03*
X81929Y108268D03*
X89803D03*
G54D41*
X468859Y115666D03*
Y141650D03*
X488859Y115666D03*
X478859D03*
X483859Y125666D03*
X473859D03*
X478859Y141650D03*
X488859D03*
X473859Y151650D03*
X483859D03*
X498859Y115666D03*
X503859Y125666D03*
X493859D03*
X498859Y141650D03*
X493859Y151650D03*
X1338938Y115666D03*
X1343938Y125666D03*
X1338938Y141650D03*
X1343938Y151650D03*
X1358938Y115666D03*
X1348938D03*
X1363938Y125666D03*
X1353938D03*
X1348938Y141650D03*
X1358938D03*
X1353938Y151650D03*
X1363938D03*
X1368938Y115666D03*
X1373938Y125666D03*
X1368938Y141650D03*
G54D51*
G01X101739Y60261D02*
Y62813D01*
G01X102400Y59600D02*
X101739Y60261D01*
G54D33*
X354460Y121642D03*
Y130142D03*
X361940Y121642D03*
Y130142D03*
X618140Y120258D03*
X610660D03*
X618140Y112158D03*
X610660D03*
X1225160Y126242D03*
Y134542D03*
X1232640Y126242D03*
Y134542D03*
X1480760Y117558D03*
Y126358D03*
X1488240Y117558D03*
Y126358D03*
G54D42*
X452875Y131650D03*
X455867Y153658D03*
X452875Y194642D03*
X516851Y140666D03*
X519843Y115666D03*
Y194642D03*
X1322954Y131650D03*
Y194642D03*
X1325946Y153658D03*
X1389922Y115666D03*
X1386930Y140666D03*
X1389922Y194642D03*
G54D24*
X101739Y65963D03*
Y62813D03*
X111958Y62925D03*
Y66075D03*
X121958Y62925D03*
Y66075D03*
X116958Y62925D03*
Y66075D03*
X106958Y62925D03*
Y66075D03*
X111958Y76125D03*
X121958D03*
X116958D03*
X106958D03*
X111958Y79275D03*
X121958D03*
X116958D03*
X106958D03*
X358259Y93869D03*
Y90719D03*
X362759Y93869D03*
Y90719D03*
X403600Y9925D03*
Y13075D03*
X408200Y9925D03*
Y13075D03*
X412800Y10025D03*
Y13175D03*
X417200Y10025D03*
Y13175D03*
X477630Y83278D03*
Y86428D03*
X483258Y87208D03*
Y84058D03*
X487558D03*
Y87208D03*
X496242D03*
Y84058D03*
X500558D03*
Y87208D03*
X504842Y84058D03*
Y87208D03*
X571700Y10425D03*
Y13575D03*
X567300Y10425D03*
Y13575D03*
X562800Y10425D03*
Y13575D03*
X576100Y10425D03*
Y13575D03*
X1229324Y93574D03*
Y90424D03*
X1233524Y93574D03*
Y90424D03*
X1272600Y8825D03*
Y11975D03*
X1281600Y8825D03*
Y11975D03*
X1277000Y8825D03*
Y11975D03*
X1286000Y8825D03*
Y11975D03*
X1350257Y84185D03*
Y87335D03*
X1355642Y86908D03*
Y83758D03*
X1359942D03*
Y86908D03*
X1364258Y83692D03*
Y86842D03*
X1345558Y84213D03*
Y87363D03*
X1368658Y86842D03*
Y83692D03*
X1376358Y83313D03*
Y86463D03*
X1433400Y10625D03*
Y13775D03*
X1447000Y10725D03*
Y13875D03*
X1437900Y10625D03*
Y13775D03*
X1442600Y10725D03*
Y13875D03*
G54D15*
X8741Y194095D03*
X13741D03*
X18741D03*
X23741D03*
X28741D03*
X33741D03*
G54D52*
G01X128600Y114510D02*
X112300D01*
X108790Y118020D01*
X88800D01*
X63680Y143140D01*
X52650D01*
X43130Y152660D01*
X32640D01*
X13741Y171559D01*
Y194095D01*
G01X102590Y115680D02*
X87830D01*
X62910Y140600D01*
X41100D01*
X8741Y172959D01*
Y194095D01*
G01X132500Y110100D02*
Y114544D01*
X129244Y117800D01*
X114200D01*
X111640Y120360D01*
X89770D01*
X64630Y145500D01*
X53600D01*
X44100Y155000D01*
X35200D01*
X18741Y171459D01*
Y194095D01*
G01X115400Y120270D02*
X112970Y122700D01*
X90740D01*
X65310Y148130D01*
X55108D01*
X45898Y157340D01*
X40650D01*
X23741Y174249D01*
Y194095D01*
G01X107390Y125110D02*
X91641D01*
X66281Y150470D01*
X56078D01*
X46868Y159680D01*
X41620D01*
X28741Y172559D01*
Y194095D01*
G01X99100Y127470D02*
X92591D01*
X67251Y152810D01*
X57048D01*
X47838Y162020D01*
X42680D01*
X33741Y170959D01*
Y194095D01*
G01X101739Y65963D02*
X92738D01*
X89803Y68898D01*
G01X111958Y76125D02*
Y73600D01*
G01D02*
Y66075D01*
G01X121958Y76125D02*
Y70900D01*
G01D02*
Y66075D01*
G01X116958Y76125D02*
Y68600D01*
G01D02*
Y66075D01*
G01X106958Y76125D02*
Y68500D01*
G01D02*
Y66075D01*
G01X353615Y114657D02*
X357800D01*
G01D02*
X361285D01*
G01Y108561D02*
X357600D01*
G01D02*
X353615D01*
G01Y102961D02*
X356861D01*
G01D02*
X361285D01*
G01X398307Y40511D02*
Y35000D01*
G01Y40511D02*
Y46100D01*
G01X396732Y72795D02*
Y78932D01*
G01X407756Y40511D02*
Y46100D01*
G01Y40511D02*
Y35156D01*
X407600Y35000D01*
G01X417205Y40511D02*
Y46100D01*
G01Y40511D02*
Y35000D01*
G01X412480Y72795D02*
Y80900D01*
G01X403032Y72795D02*
Y89532D01*
G01X415630Y72795D02*
Y80700D01*
G01X418780Y72795D02*
Y81708D01*
X414888Y85600D01*
X412300D01*
G01X409331Y72795D02*
Y88600D01*
G01X406181Y72795D02*
Y82300D01*
G01X399882Y72795D02*
Y79318D01*
G01X426654Y40511D02*
Y46100D01*
G01Y40511D02*
Y35154D01*
X426500Y35000D01*
G01X425079Y72795D02*
Y76979D01*
X426200Y78100D01*
G01X421929Y72795D02*
Y78400D01*
G01X460285Y95915D02*
X457515D01*
X453900Y92300D01*
G01X468637Y87558D02*
X466200D01*
G01X460285Y91615D02*
X458115D01*
X453300Y86800D01*
G01X460285Y87315D02*
Y83015D01*
G01D02*
X452715D01*
X451100Y81400D01*
G01X468637Y83258D02*
X466100D01*
G01X460285Y100215D02*
X455315D01*
X452100Y97000D01*
G01X452000Y102200D02*
Y102300D01*
X454215Y104515D01*
X460285D01*
G01X488800Y73700D02*
Y69700D01*
X486800Y67700D01*
Y50327D01*
X490276Y46851D01*
G01X474528Y52362D02*
Y75698D01*
X477630Y78800D01*
G01X482402Y51969D02*
Y73444D01*
X487558Y78600D01*
G01X490276Y35827D02*
X493900Y39451D01*
Y53100D01*
X496242Y55442D01*
Y78600D01*
G01X474528Y46851D02*
X470700Y50679D01*
Y68800D01*
X471787Y69887D01*
Y78400D01*
G01X477630Y78800D02*
Y83278D01*
G01X487558Y84058D02*
X483258D01*
G01X487558Y78600D02*
Y84058D01*
G01X471787Y87558D02*
Y83258D01*
G01Y87558D02*
Y89053D01*
X474692Y91958D01*
G01X471787Y78400D02*
Y83258D01*
G01X498150Y51969D02*
X504842Y58661D01*
Y78684D01*
G01X513963Y83242D02*
X515842D01*
X520439Y87839D01*
Y91000D01*
G01D02*
X515578Y95861D01*
X513787D01*
G01X513963Y87442D02*
Y89500D01*
X513787Y89676D01*
Y91561D01*
G01X513963Y87442D02*
X516500D01*
G01X496242Y84058D02*
X500558D01*
G01X496242Y78600D02*
Y84058D01*
G01X510813Y83242D02*
Y87442D01*
G01X504842Y84058D02*
X507184D01*
X508000Y83242D01*
X510813D01*
G01X504842Y78684D02*
Y84058D01*
G01X525700Y99300D02*
X520539Y104461D01*
X513787D01*
G01X519400Y96400D02*
X515639Y100161D01*
X513787D01*
G01X557048Y40512D02*
Y35148D01*
X556900Y35000D01*
G01X557048Y40512D02*
Y46100D01*
G01X547599Y40512D02*
Y46100D01*
G01Y40512D02*
Y35000D01*
G01X558623Y72796D02*
Y79200D01*
G01X552324Y72796D02*
Y78500D01*
G01X546024Y72796D02*
Y79200D01*
G01X555473Y72796D02*
Y79373D01*
X563800Y87700D01*
G01X549174Y72796D02*
Y89400D01*
G01X575946Y40512D02*
Y46100D01*
G01Y40512D02*
Y35146D01*
X575800Y35000D01*
G01X566497Y40512D02*
Y46100D01*
G01Y40512D02*
Y35000D01*
G01X571221Y72796D02*
Y79700D01*
G01X568072Y72796D02*
Y81500D01*
G01X564922Y72796D02*
Y81900D01*
G01X561772Y72796D02*
Y80800D01*
G01X574371Y72796D02*
Y78400D01*
G01X611415Y90157D02*
X614900D01*
G01D02*
X619613D01*
G01X611415Y95139D02*
X615600D01*
G01D02*
X619613D01*
G01Y100157D02*
X615500D01*
G01D02*
X611415D01*
G01Y105157D02*
X615500D01*
G01D02*
X619613D01*
G01X713900Y60500D02*
X712150Y62250D01*
X677495D01*
X674345Y59100D01*
X664700D01*
X661421Y55821D01*
Y16886D01*
X664921Y13386D01*
G01X672795Y13780D02*
X669321Y17254D01*
Y53200D01*
X672021Y55900D01*
X674456D01*
X678466Y59910D01*
X705590D01*
X707600Y57900D01*
G01X672795Y8268D02*
X677021Y12494D01*
Y55155D01*
X679436Y57570D01*
X698151D01*
X702610Y53111D01*
G01X670414Y101968D02*
Y96486D01*
G01X660965Y101968D02*
X658932D01*
X658400Y102500D01*
G01X659390Y111850D02*
Y117490D01*
G01X668839Y111850D02*
Y117661D01*
G01X689311Y101968D02*
Y96311D01*
G01X679862Y101968D02*
Y96538D01*
G01X678288Y111850D02*
Y122700D01*
G01X697185Y111850D02*
Y117385D01*
G01X687736Y111850D02*
Y118700D01*
G01X698760Y101968D02*
X701732D01*
G01X735807D02*
Y96593D01*
G01X734232Y111850D02*
X731950D01*
G01X743681D02*
Y117400D01*
G01X764153Y101968D02*
Y96153D01*
G01X754704Y101968D02*
Y96196D01*
G01X745256Y101968D02*
Y96044D01*
G01X753130Y111850D02*
Y117300D01*
G01X762578Y111850D02*
Y117300D01*
G01X773602Y101968D02*
X776032D01*
G01X772027Y111850D02*
Y117300D01*
G01X1230985Y119561D02*
X1226900D01*
G01D02*
X1223263D01*
G01Y114043D02*
X1226900D01*
G01D02*
X1230985D01*
G01Y108361D02*
X1227000D01*
G01D02*
X1223263D01*
G01Y102861D02*
X1227100D01*
G01D02*
X1230985D01*
G01X1268386Y40512D02*
Y35000D01*
G01Y40512D02*
Y46100D01*
G01X1266811Y72796D02*
Y78300D01*
G01X1273111Y72796D02*
Y89100D01*
G01X1269961Y72796D02*
Y78400D01*
G01X1296733Y40512D02*
Y46100D01*
G01Y40512D02*
Y35133D01*
X1296600Y35000D01*
G01X1287284Y40512D02*
Y46100D01*
G01Y40512D02*
Y35000D01*
G01X1277835Y40512D02*
Y46100D01*
G01Y40512D02*
Y35135D01*
X1277700Y35000D01*
G01X1295158Y72796D02*
Y79158D01*
G01X1292008Y72796D02*
Y80192D01*
G01X1288859Y72796D02*
Y78400D01*
G01X1279410Y72796D02*
Y87200D01*
G01X1285709Y72796D02*
Y84300D01*
G01X1276260Y72796D02*
Y79000D01*
G01X1282559Y72796D02*
Y85700D01*
G01X1341187Y78400D02*
Y50271D01*
X1344607Y46851D01*
G01X1338037Y87558D02*
X1333400Y82921D01*
Y82900D01*
G01X1329737Y99239D02*
X1323000D01*
G01X1329500Y81400D02*
X1330500Y80400D01*
X1335179D01*
X1338037Y83258D01*
G01X1329637Y94639D02*
X1323239D01*
X1321400Y92800D01*
G01X1321500Y82600D02*
X1324100D01*
X1327339Y85839D01*
X1329637D01*
G01Y90339D02*
X1325039D01*
X1322500Y87800D01*
G01X1341187Y83258D02*
X1342958D01*
X1343913Y84213D01*
X1345558D01*
G01X1341187Y87558D02*
Y83258D01*
G01D02*
Y78400D01*
G01X1358200Y69000D02*
X1356879Y67679D01*
Y50327D01*
X1360355Y46851D01*
G01X1344607Y52362D02*
Y74807D01*
X1348300Y78500D01*
G01X1352481Y51969D02*
Y73481D01*
X1357700Y78700D01*
G01X1360355Y35827D02*
X1364258Y39730D01*
Y59858D01*
X1365900Y61500D01*
Y73600D01*
X1364258Y75242D01*
Y78700D01*
G01X1348300Y78500D02*
X1350257Y80457D01*
Y84185D01*
G01X1359942Y83758D02*
X1355642D01*
G01X1357700Y78700D02*
X1359942Y80942D01*
Y83758D01*
G01X1368658Y83692D02*
X1364258D01*
G01Y78700D02*
Y83692D01*
G01X1368229Y51969D02*
X1376358Y60098D01*
Y78700D01*
G01X1384163Y91561D02*
Y87242D01*
G01D02*
X1387400D01*
G01X1389900Y97600D02*
X1387339Y100161D01*
X1384287D01*
G01X1384163Y83042D02*
X1386642D01*
X1391000Y87400D01*
Y92400D01*
G01D02*
X1388339Y95061D01*
X1385087D01*
X1384287Y95861D01*
G01X1381013Y83042D02*
X1378971D01*
X1378700Y83313D01*
X1376358D01*
G01X1381013Y83042D02*
Y87242D01*
G01X1376358Y78700D02*
Y83313D01*
G01X1395200Y99500D02*
X1390239Y104461D01*
X1384287D01*
G01X1417678Y40511D02*
Y46100D01*
G01Y40511D02*
Y35000D01*
G01X1427127Y40511D02*
Y46100D01*
G01Y40511D02*
Y35127D01*
X1427000Y35000D01*
G01X1416103Y72795D02*
Y78400D01*
G01X1422403Y72795D02*
Y78400D01*
G01X1425552Y72795D02*
Y79452D01*
X1434200Y88100D01*
G01X1435001Y72795D02*
Y81700D01*
G01X1431851Y72795D02*
Y80200D01*
G01X1428702Y72795D02*
Y79002D01*
G01X1419253Y72795D02*
Y78560D01*
X1429193Y88500D01*
X1429400D01*
G01X1446025Y40511D02*
Y46100D01*
G01Y40511D02*
Y35125D01*
X1445900Y35000D01*
G01X1436576Y40511D02*
Y35000D01*
G01Y40511D02*
Y46100D01*
G01X1444450Y72795D02*
Y78300D01*
G01X1441300Y72795D02*
Y79100D01*
G01X1438151Y72795D02*
Y81100D01*
G01X1481215Y93057D02*
X1484700D01*
G01X1481215Y98057D02*
X1485000D01*
G01X1481215Y103257D02*
X1484900D01*
G01X1481215Y109357D02*
X1484800D01*
G01X1484700Y93057D02*
X1488313D01*
G01Y98057D02*
X1485000D01*
G01X1484900Y103257D02*
X1488313D01*
G01Y109357D02*
X1484800D01*
G01X1579300Y57900D02*
X1577090Y60110D01*
X1549971D01*
X1546961Y57100D01*
X1543300D01*
X1539400Y53200D01*
Y17254D01*
X1542874Y13780D01*
G01Y8268D02*
X1547100Y12494D01*
Y53928D01*
X1550942Y57770D01*
X1568030D01*
X1572300Y53500D01*
G01X1586100Y60500D02*
X1584150Y62450D01*
X1549001D01*
X1545991Y59440D01*
X1534940D01*
X1531500Y56000D01*
Y16886D01*
X1535000Y13386D01*
G01X1549940Y101968D02*
Y96538D01*
G01X1540492Y101968D02*
Y96486D01*
G01X1531043Y101968D02*
X1529010D01*
X1528478Y102500D01*
G01X1548366Y111850D02*
Y122700D01*
G01X1538917Y111850D02*
Y117661D01*
G01X1529468Y111850D02*
Y117490D01*
G01X1559389Y101968D02*
Y96311D01*
G01X1568838Y101968D02*
X1571810D01*
G01X1557814Y111850D02*
Y118700D01*
G01X1567263Y111850D02*
Y117385D01*
G01X1605886Y101968D02*
Y96594D01*
X1605885Y96593D01*
G01X1615335Y101968D02*
Y96045D01*
X1615334Y96044D01*
G01X1613760Y111850D02*
Y117399D01*
X1613759Y117400D01*
G01X1604311Y111850D02*
X1602028D01*
G01X1624783Y101968D02*
Y96197D01*
X1624782Y96196D01*
G01X1634232Y101968D02*
Y96154D01*
X1634231Y96153D01*
G01X1642106Y111850D02*
Y117299D01*
X1642105Y117300D01*
G01X1632657Y111850D02*
Y117299D01*
X1632656Y117300D01*
G01X1623208D02*
X1623209Y117299D01*
Y111850D01*
G01X1643681Y101968D02*
X1646110D01*
G54D43*
X463859Y176650D03*
X508859D03*
X1333938D03*
X1378938D03*
G54D25*
X306772Y19685D03*
Y41850D03*
X612047Y19685D03*
Y41850D03*
X1176851Y19685D03*
Y41850D03*
X1482126Y19685D03*
Y41850D03*
G54D34*
X352092Y139282D03*
X351992Y149118D03*
X363509Y139282D03*
X363409Y149118D03*
X621908Y148982D03*
X610491D03*
X622013Y158618D03*
X610596D03*
X1222199Y143895D03*
X1222304Y153605D03*
X1233616Y143895D03*
X1233721Y153605D03*
X1480708Y162291D03*
X1480794Y152600D03*
X1492125Y162291D03*
X1492211Y152600D03*
G54D16*
X40827Y29528D03*
Y147638D03*
G54D53*
G01X408200Y13075D02*
X403600D01*
G01X400100Y13900D02*
X400925Y13075D01*
X403600D01*
G01X412800Y13175D02*
X417200D01*
G01X412800D02*
Y16200D01*
G01X410906Y40511D02*
Y46100D01*
G01X414055Y40511D02*
Y46200D01*
G01X463435Y83015D02*
Y79865D01*
G01X487558Y87208D02*
Y89358D01*
X488000Y89800D01*
G01X477630Y86428D02*
Y88900D01*
G01D02*
X477842Y89112D01*
Y91958D01*
G01X504842Y87208D02*
X500558D01*
G01X504842D02*
Y89342D01*
X505700Y90200D01*
G01X562800Y13575D02*
X559425D01*
G01X560198Y40512D02*
Y46100D01*
G01X571700Y13575D02*
X576100D01*
G01D02*
X579525D01*
X582416Y16466D01*
G01X567300Y13575D02*
X562800D01*
G01X563347Y40512D02*
Y46100D01*
G01X667200Y75700D02*
X670425Y78925D01*
Y82539D01*
G01X680300Y75600D02*
X679874Y76026D01*
Y82539D01*
G01X689723Y89400D02*
X689323Y89000D01*
Y82539D01*
G01X740300Y87300D02*
Y85200D01*
X742961Y82539D01*
X745268D01*
G01X753100Y75100D02*
Y76200D01*
X754716Y77816D01*
Y82539D01*
G01X765600Y74800D02*
Y76800D01*
X764165Y78235D01*
Y82539D01*
G01X1272600Y11975D02*
X1277000D01*
G01X1268700Y14000D02*
X1270700Y12000D01*
Y11975D01*
X1272600D01*
G01X1286000D02*
X1281600D01*
G01X1286000D02*
X1289775D01*
G01X1284134Y40512D02*
Y46100D01*
G01X1280985Y40512D02*
Y46200D01*
G01X1340400Y90800D02*
X1342121D01*
X1345558Y87363D01*
G01X1359942Y86908D02*
X1360008Y86842D01*
X1364258D01*
G01X1359942Y86908D02*
Y90058D01*
X1359000Y91000D01*
G01X1345558Y87363D02*
X1345586Y87335D01*
X1350257D01*
G01X1376358Y86463D02*
X1371600D01*
G01X1368658Y86842D02*
Y93058D01*
X1371600Y96000D01*
G01X1433400Y13775D02*
X1429525D01*
G01X1437900D02*
X1433400D01*
G01X1433426Y40511D02*
Y46100D01*
G01X1430277Y40511D02*
Y46100D01*
G01X1442600Y13875D02*
X1447000D01*
G01D02*
X1450875D01*
X1454600Y17600D01*
G01X1537279Y75700D02*
X1540504Y78925D01*
Y82539D01*
G01X1550500Y75500D02*
X1549953Y76047D01*
Y82539D01*
G01X1559802Y89400D02*
X1559402Y89000D01*
Y82539D01*
G01X1610379Y87300D02*
Y85200D01*
X1613040Y82539D01*
X1615347D01*
G01X1623179Y75100D02*
Y76200D01*
X1624795Y77816D01*
Y82539D01*
G01X1635679Y74800D02*
Y76800D01*
X1634244Y78235D01*
Y82539D01*
G54D26*
X306772Y67913D03*
X612047D03*
X1176851D03*
X1482126D03*
G54D44*
X506024Y8268D03*
X688543D03*
X1376103D03*
X1558622D03*
G54D17*
X44528Y41339D03*
Y53150D03*
X56339Y41339D03*
Y53150D03*
X44528Y64961D03*
Y76772D03*
X56339Y64961D03*
Y76772D03*
X44528Y88583D03*
Y100394D03*
X56339Y88583D03*
Y100394D03*
X44528Y112205D03*
Y124016D03*
X56339Y112205D03*
Y124016D03*
X44528Y135827D03*
X392795Y56653D03*
X542087Y56654D03*
X655453Y132244D03*
X702697D03*
X730295D03*
X777539D03*
X1262874Y56654D03*
X1412166Y56653D03*
X1525531Y132244D03*
X1572775D03*
X1600374D03*
X1647618D03*
G54D35*
X392776Y32264D03*
X383642Y50375D03*
Y70060D03*
Y88564D03*
X411673Y32264D03*
X430571D03*
X439744Y50375D03*
Y70060D03*
Y88564D03*
X532934Y50375D03*
Y70060D03*
Y88564D03*
X542068Y32264D03*
X560965D03*
X579863D03*
X589036Y50375D03*
Y70060D03*
Y88564D03*
X1262855Y32264D03*
X1253721Y50375D03*
Y70060D03*
Y88564D03*
X1281752Y32264D03*
X1300650D03*
X1309823Y50375D03*
Y70060D03*
Y88564D03*
X1412146Y32264D03*
X1403012Y50375D03*
Y70060D03*
Y88564D03*
X1431043Y32264D03*
X1449941D03*
X1459114Y50375D03*
Y70060D03*
Y88564D03*
G54D54*
G01X457212Y-338900D02*
Y-343900D01*
G01X455755Y-338900D02*
X458669D01*
G01X463579Y-343900D02*
X461045D01*
Y-338900D01*
X463579D01*
G01X462565Y-341317D02*
X461045D01*
G01X466145Y-338900D02*
Y-343900D01*
X468679D01*
G01X472512Y-344067D02*
X472385Y-343983D01*
Y-343817D01*
X472512Y-343733D01*
X472639Y-343817D01*
Y-343983D01*
X472512Y-344067D01*
G01Y-341817D02*
X472385Y-341733D01*
Y-341567D01*
X472512Y-341483D01*
X472639Y-341567D01*
Y-341733D01*
X472512Y-341817D01*
G01X477295Y-345567D02*
X476662Y-344733D01*
X476345Y-343900D01*
Y-340567D01*
X476662Y-339733D01*
X477295Y-338900D01*
G01X482712D02*
X482205Y-339067D01*
X481825Y-339483D01*
X481572Y-339983D01*
X481382Y-340650D01*
X481319Y-341400D01*
X481382Y-342150D01*
X481572Y-342817D01*
X481825Y-343317D01*
X482205Y-343733D01*
X482712Y-343900D01*
X483219Y-343733D01*
X483599Y-343317D01*
X483852Y-342817D01*
X484042Y-342150D01*
X484105Y-341400D01*
X484042Y-340650D01*
X483852Y-339983D01*
X483599Y-339483D01*
X483219Y-339067D01*
X482712Y-338900D01*
G01X486419Y-342900D02*
X486799Y-343483D01*
X487305Y-343817D01*
X487875Y-343900D01*
X488382Y-343817D01*
X488889Y-343400D01*
X489205Y-342900D01*
X489269Y-342400D01*
X489142Y-341817D01*
X488699Y-341400D01*
X488255Y-341233D01*
X487685D01*
G01X488255D02*
X488635Y-340983D01*
X488952Y-340567D01*
X489079Y-340067D01*
X488952Y-339567D01*
X488635Y-339150D01*
X488065Y-338900D01*
X487495Y-338983D01*
X486925Y-339317D01*
G01X493229Y-345567D02*
X493862Y-344733D01*
X494179Y-343900D01*
Y-340567D01*
X493862Y-339733D01*
X493229Y-338900D01*
G01X496619Y-342900D02*
X496999Y-343483D01*
X497505Y-343817D01*
X498075Y-343900D01*
X498582Y-343817D01*
X499089Y-343400D01*
X499405Y-342900D01*
X499469Y-342400D01*
X499342Y-341817D01*
X498899Y-341400D01*
X498455Y-341233D01*
X497885D01*
G01X498455D02*
X498835Y-340983D01*
X499152Y-340567D01*
X499279Y-340067D01*
X499152Y-339567D01*
X498835Y-339150D01*
X498265Y-338900D01*
X497695Y-338983D01*
X497125Y-339317D01*
G01X501909Y-339733D02*
X502289Y-339233D01*
X502732Y-338983D01*
X503239Y-338900D01*
X503872Y-339067D01*
X504315Y-339483D01*
X504442Y-339983D01*
X504379Y-340483D01*
X504125Y-340900D01*
X502859Y-341733D01*
X502289Y-342317D01*
X501909Y-343150D01*
X501782Y-343900D01*
X504442D01*
G01X508085D02*
X508212Y-342817D01*
X508402Y-341900D01*
X508655Y-341067D01*
X508972Y-340150D01*
X509479Y-338900D01*
X506945D01*
G01X512489Y-342233D02*
X514135D01*
G01X517209Y-339733D02*
X517589Y-339233D01*
X518032Y-338983D01*
X518539Y-338900D01*
X519172Y-339067D01*
X519615Y-339483D01*
X519742Y-339983D01*
X519679Y-340483D01*
X519425Y-340900D01*
X518159Y-341733D01*
X517589Y-342317D01*
X517209Y-343150D01*
X517082Y-343900D01*
X519742D01*
G01X522119Y-342900D02*
X522499Y-343483D01*
X523005Y-343817D01*
X523575Y-343900D01*
X524082Y-343817D01*
X524589Y-343400D01*
X524905Y-342900D01*
X524969Y-342400D01*
X524842Y-341817D01*
X524399Y-341400D01*
X523955Y-341233D01*
X523385D01*
G01X523955D02*
X524335Y-340983D01*
X524652Y-340567D01*
X524779Y-340067D01*
X524652Y-339567D01*
X524335Y-339150D01*
X523765Y-338900D01*
X523195Y-338983D01*
X522625Y-339317D01*
G01X529372Y-343900D02*
Y-338900D01*
X527029Y-342483D01*
X530195D01*
G01X532319Y-343150D02*
X532699Y-343567D01*
X533142Y-343817D01*
X533712Y-343900D01*
X534282Y-343733D01*
X534725Y-343400D01*
X535042Y-342817D01*
X535105Y-342150D01*
X534979Y-341483D01*
X534662Y-341067D01*
X534219Y-340733D01*
X533775Y-340650D01*
X533332Y-340733D01*
X532762Y-341067D01*
X532952Y-338900D01*
X534662D01*
G01X542709Y-343900D02*
Y-338900D01*
X545115D01*
G01X544229Y-341317D02*
X542709D01*
G01X547429Y-343900D02*
X549012Y-338900D01*
X550595Y-343900D01*
G01X550025Y-342150D02*
X547999D01*
G01X552782Y-343900D02*
X555442Y-338900D01*
G01X552782D02*
X555442Y-343900D01*
G01X559212Y-344067D02*
X559085Y-343983D01*
Y-343817D01*
X559212Y-343733D01*
X559339Y-343817D01*
Y-343983D01*
X559212Y-344067D01*
G01Y-341817D02*
X559085Y-341733D01*
Y-341567D01*
X559212Y-341483D01*
X559339Y-341567D01*
Y-341733D01*
X559212Y-341817D01*
G01X563995Y-345567D02*
X563362Y-344733D01*
X563045Y-343900D01*
Y-340567D01*
X563362Y-339733D01*
X563995Y-338900D01*
G01X569412D02*
X568905Y-339067D01*
X568525Y-339483D01*
X568272Y-339983D01*
X568082Y-340650D01*
X568019Y-341400D01*
X568082Y-342150D01*
X568272Y-342817D01*
X568525Y-343317D01*
X568905Y-343733D01*
X569412Y-343900D01*
X569919Y-343733D01*
X570299Y-343317D01*
X570552Y-342817D01*
X570742Y-342150D01*
X570805Y-341400D01*
X570742Y-340650D01*
X570552Y-339983D01*
X570299Y-339483D01*
X569919Y-339067D01*
X569412Y-338900D01*
G01X573119Y-342900D02*
X573499Y-343483D01*
X574005Y-343817D01*
X574575Y-343900D01*
X575082Y-343817D01*
X575589Y-343400D01*
X575905Y-342900D01*
X575969Y-342400D01*
X575842Y-341817D01*
X575399Y-341400D01*
X574955Y-341233D01*
X574385D01*
G01X574955D02*
X575335Y-340983D01*
X575652Y-340567D01*
X575779Y-340067D01*
X575652Y-339567D01*
X575335Y-339150D01*
X574765Y-338900D01*
X574195Y-338983D01*
X573625Y-339317D01*
G01X579929Y-345567D02*
X580562Y-344733D01*
X580879Y-343900D01*
Y-340567D01*
X580562Y-339733D01*
X579929Y-338900D01*
G01X583319Y-342900D02*
X583699Y-343483D01*
X584205Y-343817D01*
X584775Y-343900D01*
X585282Y-343817D01*
X585789Y-343400D01*
X586105Y-342900D01*
X586169Y-342400D01*
X586042Y-341817D01*
X585599Y-341400D01*
X585155Y-341233D01*
X584585D01*
G01X585155D02*
X585535Y-340983D01*
X585852Y-340567D01*
X585979Y-340067D01*
X585852Y-339567D01*
X585535Y-339150D01*
X584965Y-338900D01*
X584395Y-338983D01*
X583825Y-339317D01*
G01X588735Y-343317D02*
X589179Y-343733D01*
X589685Y-343900D01*
X590192Y-343733D01*
X590635Y-343233D01*
X590952Y-342483D01*
X591079Y-341733D01*
Y-340817D01*
X590952Y-340067D01*
X590635Y-339400D01*
X590255Y-339067D01*
X589812Y-338900D01*
X589305Y-339067D01*
X588925Y-339400D01*
X588672Y-339900D01*
X588545Y-340567D01*
X588672Y-341150D01*
X588989Y-341733D01*
X589369Y-342067D01*
X589812Y-342150D01*
X590319Y-341983D01*
X590699Y-341567D01*
X591079Y-340817D01*
G01X594785Y-343900D02*
X594912Y-342817D01*
X595102Y-341900D01*
X595355Y-341067D01*
X595672Y-340150D01*
X596179Y-338900D01*
X593645D01*
G01X599189Y-342233D02*
X600835D01*
G01X603719Y-342900D02*
X604099Y-343483D01*
X604605Y-343817D01*
X605175Y-343900D01*
X605682Y-343817D01*
X606189Y-343400D01*
X606505Y-342900D01*
X606569Y-342400D01*
X606442Y-341817D01*
X605999Y-341400D01*
X605555Y-341233D01*
X604985D01*
G01X605555D02*
X605935Y-340983D01*
X606252Y-340567D01*
X606379Y-340067D01*
X606252Y-339567D01*
X605935Y-339150D01*
X605365Y-338900D01*
X604795Y-338983D01*
X604225Y-339317D01*
G01X609009Y-341817D02*
X609452Y-341233D01*
X609832Y-340900D01*
X610339Y-340733D01*
X610782Y-340900D01*
X611099Y-341233D01*
X611352Y-341733D01*
X611415Y-342317D01*
X611352Y-342817D01*
X611099Y-343317D01*
X610719Y-343733D01*
X610275Y-343900D01*
X609769Y-343733D01*
X609325Y-343233D01*
X609072Y-342483D01*
X609009Y-341650D01*
X609135Y-340567D01*
X609325Y-339983D01*
X609642Y-339400D01*
X610085Y-338983D01*
X610529Y-338900D01*
X610972Y-339067D01*
X611289Y-339483D01*
G01X615312Y-343900D02*
Y-338900D01*
X614552Y-339900D01*
G01Y-343900D02*
X616072D01*
G01X621172D02*
Y-338900D01*
X618829Y-342483D01*
X621995D01*
G01X445212Y-273900D02*
Y-348900D01*
X945212D01*
Y-273900D01*
X445212D01*
G01X640212D02*
Y-348900D01*
G01Y-323900D02*
X743212D01*
Y-298900D01*
G01X640212D02*
X743212D01*
G01Y-273900D02*
Y-348900D01*
G01X745212Y-273900D02*
Y-348900D01*
G01X750719Y-333900D02*
Y-328900D01*
X751985D01*
X752492Y-329150D01*
X752872Y-329483D01*
X753189Y-329983D01*
X753442Y-330567D01*
X753505Y-331400D01*
X753442Y-332233D01*
X753189Y-332817D01*
X752872Y-333317D01*
X752492Y-333650D01*
X751985Y-333900D01*
X750719D01*
G01X755629D02*
X757212Y-328900D01*
X758795Y-333900D01*
G01X758225Y-332150D02*
X756199D01*
G01X762312Y-328900D02*
Y-333900D01*
G01X760855Y-328900D02*
X763769D01*
G01X768679Y-333900D02*
X766145D01*
Y-328900D01*
X768679D01*
G01X767665Y-331317D02*
X766145D01*
G01X772512Y-334067D02*
X772385Y-333983D01*
Y-333817D01*
X772512Y-333733D01*
X772639Y-333817D01*
Y-333983D01*
X772512Y-334067D01*
G01Y-331817D02*
X772385Y-331733D01*
Y-331567D01*
X772512Y-331483D01*
X772639Y-331567D01*
Y-331733D01*
X772512Y-331817D01*
G01X745212Y-323900D02*
X945212D01*
G01X750845Y-308900D02*
Y-303900D01*
X752365D01*
X752872Y-304150D01*
X753252Y-304733D01*
X753379Y-305400D01*
X753252Y-306067D01*
X752935Y-306567D01*
X752365Y-306817D01*
X750845D01*
G01X756072Y-309067D02*
X758352Y-303900D01*
G01X760855Y-308900D02*
Y-303900D01*
X763769Y-308900D01*
Y-303900D01*
G01X767412Y-309067D02*
X767285Y-308983D01*
Y-308817D01*
X767412Y-308733D01*
X767539Y-308817D01*
Y-308983D01*
X767412Y-309067D01*
G01Y-306817D02*
X767285Y-306733D01*
Y-306567D01*
X767412Y-306483D01*
X767539Y-306567D01*
Y-306733D01*
X767412Y-306817D01*
G01X745212Y-298900D02*
X945212D01*
G01X750845Y-283900D02*
Y-278900D01*
X752365D01*
X752872Y-279150D01*
X753252Y-279733D01*
X753379Y-280400D01*
X753252Y-281067D01*
X752935Y-281567D01*
X752365Y-281817D01*
X750845D01*
G01X755945Y-283900D02*
Y-278900D01*
X757529D01*
X758035Y-279150D01*
X758352Y-279483D01*
X758479Y-280150D01*
X758352Y-280817D01*
X757972Y-281233D01*
X757529Y-281483D01*
X755945D01*
G01X757529D02*
X758479Y-283900D01*
G01X762312D02*
X761805Y-283817D01*
X761362Y-283483D01*
X760982Y-282983D01*
X760729Y-282400D01*
X760602Y-281733D01*
Y-281067D01*
X760729Y-280400D01*
X760982Y-279817D01*
X761362Y-279317D01*
X761805Y-278983D01*
X762312Y-278900D01*
X762819Y-278983D01*
X763262Y-279317D01*
X763642Y-279817D01*
X763895Y-280400D01*
X764022Y-281067D01*
Y-281733D01*
X763895Y-282400D01*
X763642Y-282983D01*
X763262Y-283483D01*
X762819Y-283817D01*
X762312Y-283900D01*
G01X766145Y-282900D02*
X766462Y-283400D01*
X766842Y-283733D01*
X767285Y-283900D01*
X767792Y-283733D01*
X768172Y-283400D01*
X768552Y-282900D01*
X768679Y-282233D01*
Y-278900D01*
G01X773779Y-283900D02*
X771245D01*
Y-278900D01*
X773779D01*
G01X772765Y-281317D02*
X771245D01*
G01X779005Y-279317D02*
X778625Y-279067D01*
X778182Y-278900D01*
X777675D01*
X777105Y-279150D01*
X776662Y-279567D01*
X776345Y-280067D01*
X776092Y-280900D01*
X776029Y-281650D01*
X776155Y-282400D01*
X776345Y-282900D01*
X776725Y-283400D01*
X777169Y-283733D01*
X777612Y-283900D01*
X778055D01*
X778499Y-283733D01*
X778879Y-283483D01*
X779195Y-283150D01*
G01X782712Y-278900D02*
Y-283900D01*
G01X781255Y-278900D02*
X784169D01*
G01X787812Y-284067D02*
X787685Y-283983D01*
Y-283817D01*
X787812Y-283733D01*
X787939Y-283817D01*
Y-283983D01*
X787812Y-284067D01*
G01Y-281817D02*
X787685Y-281733D01*
Y-281567D01*
X787812Y-281483D01*
X787939Y-281567D01*
Y-281733D01*
X787812Y-281817D01*
G01X860212Y-323900D02*
Y-348900D01*
G01X865845Y-333900D02*
Y-328900D01*
X867429D01*
X867935Y-329150D01*
X868252Y-329483D01*
X868379Y-330150D01*
X868252Y-330817D01*
X867872Y-331233D01*
X867429Y-331483D01*
X865845D01*
G01X867429D02*
X868379Y-333900D01*
G01X873479D02*
X870945D01*
Y-328900D01*
X873479D01*
G01X872465Y-331317D02*
X870945D01*
G01X875729Y-328900D02*
X877312Y-333900D01*
X878895Y-328900D01*
G01X882412Y-334067D02*
X882285Y-333983D01*
Y-333817D01*
X882412Y-333733D01*
X882539Y-333817D01*
Y-333983D01*
X882412Y-334067D01*
G01Y-331817D02*
X882285Y-331733D01*
Y-331567D01*
X882412Y-331483D01*
X882539Y-331567D01*
Y-331733D01*
X882412Y-331817D01*
G01X909212Y-323900D02*
Y-348900D01*
G01X-471400Y-391900D02*
Y1528800D01*
X2244200D01*
Y-391900D01*
X-471400D01*
G01X455917Y-335560D02*
X456544Y-336085D01*
X457249Y-336400D01*
X457875D01*
X458502Y-336085D01*
X458972Y-335560D01*
X459207Y-334825D01*
X459050Y-334090D01*
X458659Y-333460D01*
X457954Y-333040D01*
X457014Y-332830D01*
X456465Y-332410D01*
X456230Y-331675D01*
X456387Y-330940D01*
X456779Y-330415D01*
X457327Y-330100D01*
X457875D01*
X458424Y-330310D01*
X458894Y-330835D01*
G01X462217Y-336400D02*
Y-330100D01*
G01X465507D02*
Y-336400D01*
G01Y-333250D02*
X462217D01*
G01X469222Y-330100D02*
X471102D01*
G01X470162D02*
Y-336400D01*
G01X469222D02*
X471102D01*
G01X478029D02*
X474895D01*
Y-330100D01*
X478029D01*
G01X476775Y-333145D02*
X474895D01*
G01X480960Y-336400D02*
Y-330100D01*
X484564Y-336400D01*
Y-330100D01*
G01X488905Y-337555D02*
X489219Y-336190D01*
G01X495362Y-330100D02*
Y-336400D01*
G01X493560Y-330100D02*
X497164D01*
G01X499704Y-336400D02*
X501662Y-330100D01*
X503620Y-336400D01*
G01X502915Y-334195D02*
X500409D01*
G01X507022Y-330100D02*
X508902D01*
G01X507962D02*
Y-336400D01*
G01X507022D02*
X508902D01*
G01X511912Y-330100D02*
X513009Y-336400D01*
X514262Y-330100D01*
X515515Y-336400D01*
X516612Y-330100D01*
G01X518604Y-336400D02*
X520562Y-330100D01*
X522520Y-336400D01*
G01X521815Y-334195D02*
X519309D01*
G01X525060Y-336400D02*
Y-330100D01*
X528664Y-336400D01*
Y-330100D01*
G01X537895Y-336400D02*
Y-330100D01*
X539854D01*
X540480Y-330415D01*
X540872Y-330835D01*
X541029Y-331675D01*
X540872Y-332515D01*
X540402Y-333040D01*
X539854Y-333355D01*
X537895D01*
G01X539854D02*
X541029Y-336400D01*
G01X545762Y-336610D02*
X545605Y-336505D01*
Y-336295D01*
X545762Y-336190D01*
X545919Y-336295D01*
Y-336505D01*
X545762Y-336610D01*
G01X552062Y-336400D02*
X551435Y-336295D01*
X550887Y-335875D01*
X550417Y-335245D01*
X550104Y-334510D01*
X549947Y-333670D01*
Y-332830D01*
X550104Y-331990D01*
X550417Y-331255D01*
X550887Y-330625D01*
X551435Y-330205D01*
X552062Y-330100D01*
X552689Y-330205D01*
X553237Y-330625D01*
X553707Y-331255D01*
X554020Y-331990D01*
X554177Y-332830D01*
Y-333670D01*
X554020Y-334510D01*
X553707Y-335245D01*
X553237Y-335875D01*
X552689Y-336295D01*
X552062Y-336400D01*
G01X558362Y-336610D02*
X558205Y-336505D01*
Y-336295D01*
X558362Y-336190D01*
X558519Y-336295D01*
Y-336505D01*
X558362Y-336610D01*
G01X566385Y-330625D02*
X565915Y-330310D01*
X565367Y-330100D01*
X564740D01*
X564035Y-330415D01*
X563487Y-330940D01*
X563095Y-331570D01*
X562782Y-332620D01*
X562704Y-333565D01*
X562860Y-334510D01*
X563095Y-335140D01*
X563565Y-335770D01*
X564114Y-336190D01*
X564662Y-336400D01*
X565210D01*
X565759Y-336190D01*
X566229Y-335875D01*
X566620Y-335455D01*
G01X570962Y-336610D02*
X570805Y-336505D01*
Y-336295D01*
X570962Y-336190D01*
X571119Y-336295D01*
Y-336505D01*
X570962Y-336610D01*
G01X455839Y-326400D02*
Y-320100D01*
G01X458815D02*
X455839Y-323985D01*
G01X459285Y-326400D02*
X457170Y-322200D01*
G01X462139Y-320100D02*
Y-324615D01*
X462452Y-325560D01*
X463079Y-326190D01*
X463862Y-326400D01*
X464645Y-326190D01*
X465272Y-325560D01*
X465585Y-324615D01*
Y-320100D01*
G01X471729Y-326400D02*
X468595D01*
Y-320100D01*
X471729D01*
G01X470475Y-323145D02*
X468595D01*
G01X475522Y-320100D02*
X477402D01*
G01X476462D02*
Y-326400D01*
G01X475522D02*
X477402D01*
G01X487417Y-325560D02*
X488044Y-326085D01*
X488749Y-326400D01*
X489375D01*
X490002Y-326085D01*
X490472Y-325560D01*
X490707Y-324825D01*
X490550Y-324090D01*
X490159Y-323460D01*
X489454Y-323040D01*
X488514Y-322830D01*
X487965Y-322410D01*
X487730Y-321675D01*
X487887Y-320940D01*
X488279Y-320415D01*
X488827Y-320100D01*
X489375D01*
X489924Y-320310D01*
X490394Y-320835D01*
G01X493717Y-326400D02*
Y-320100D01*
G01X497007D02*
Y-326400D01*
G01Y-323250D02*
X493717D01*
G01X499704Y-326400D02*
X501662Y-320100D01*
X503620Y-326400D01*
G01X502915Y-324195D02*
X500409D01*
G01X506160Y-326400D02*
Y-320100D01*
X509764Y-326400D01*
Y-320100D01*
G01X518917Y-326400D02*
Y-320100D01*
G01X522207D02*
Y-326400D01*
G01Y-323250D02*
X518917D01*
G01X525217Y-325560D02*
X525844Y-326085D01*
X526549Y-326400D01*
X527175D01*
X527802Y-326085D01*
X528272Y-325560D01*
X528507Y-324825D01*
X528350Y-324090D01*
X527959Y-323460D01*
X527254Y-323040D01*
X526314Y-322830D01*
X525765Y-322410D01*
X525530Y-321675D01*
X525687Y-320940D01*
X526079Y-320415D01*
X526627Y-320100D01*
X527175D01*
X527724Y-320310D01*
X528194Y-320835D01*
G01X532222Y-320100D02*
X534102D01*
G01X533162D02*
Y-326400D01*
G01X532222D02*
X534102D01*
G01X537504D02*
X539462Y-320100D01*
X541420Y-326400D01*
G01X540715Y-324195D02*
X538209D01*
G01X543960Y-326400D02*
Y-320100D01*
X547564Y-326400D01*
Y-320100D01*
G01X552532Y-323250D02*
X554099D01*
Y-325140D01*
X553629Y-325770D01*
X553080Y-326190D01*
X552297Y-326400D01*
X551514Y-326190D01*
X550965Y-325770D01*
X550495Y-325140D01*
X550182Y-324405D01*
X550025Y-323565D01*
Y-322830D01*
X550182Y-322200D01*
X550495Y-321465D01*
X550965Y-320835D01*
X551435Y-320415D01*
X552062Y-320100D01*
X552610D01*
X553237Y-320310D01*
X553707Y-320730D01*
G01X558205Y-327555D02*
X558519Y-326190D01*
G01X564662Y-320100D02*
Y-326400D01*
G01X562860Y-320100D02*
X566464D01*
G01X569004Y-326400D02*
X570962Y-320100D01*
X572920Y-326400D01*
G01X572215Y-324195D02*
X569709D01*
G01X577262Y-326400D02*
X576635Y-326295D01*
X576087Y-325875D01*
X575617Y-325245D01*
X575304Y-324510D01*
X575147Y-323670D01*
Y-322830D01*
X575304Y-321990D01*
X575617Y-321255D01*
X576087Y-320625D01*
X576635Y-320205D01*
X577262Y-320100D01*
X577889Y-320205D01*
X578437Y-320625D01*
X578907Y-321255D01*
X579220Y-321990D01*
X579377Y-322830D01*
Y-323670D01*
X579220Y-324510D01*
X578907Y-325245D01*
X578437Y-325875D01*
X577889Y-326295D01*
X577262Y-326400D01*
G01X589862D02*
Y-323565D01*
X588295Y-320100D01*
G01X591429D02*
X589862Y-323565D01*
G01X594439Y-320100D02*
Y-324615D01*
X594752Y-325560D01*
X595379Y-326190D01*
X596162Y-326400D01*
X596945Y-326190D01*
X597572Y-325560D01*
X597885Y-324615D01*
Y-320100D01*
G01X600504Y-326400D02*
X602462Y-320100D01*
X604420Y-326400D01*
G01X603715Y-324195D02*
X601209D01*
G01X606960Y-326400D02*
Y-320100D01*
X610564Y-326400D01*
Y-320100D01*
G01X455760Y-316400D02*
Y-310100D01*
X459364Y-316400D01*
Y-310100D01*
G01X463862Y-316400D02*
X463235Y-316295D01*
X462687Y-315875D01*
X462217Y-315245D01*
X461904Y-314510D01*
X461747Y-313670D01*
Y-312830D01*
X461904Y-311990D01*
X462217Y-311255D01*
X462687Y-310625D01*
X463235Y-310205D01*
X463862Y-310100D01*
X464489Y-310205D01*
X465037Y-310625D01*
X465507Y-311255D01*
X465820Y-311990D01*
X465977Y-312830D01*
Y-313670D01*
X465820Y-314510D01*
X465507Y-315245D01*
X465037Y-315875D01*
X464489Y-316295D01*
X463862Y-316400D01*
G01X470162Y-316610D02*
X470005Y-316505D01*
Y-316295D01*
X470162Y-316190D01*
X470319Y-316295D01*
Y-316505D01*
X470162Y-316610D01*
G01X476462Y-316400D02*
Y-310100D01*
X475522Y-311360D01*
G01Y-316400D02*
X477402D01*
G01X482762D02*
X483310Y-316295D01*
X483937Y-315980D01*
X484329Y-315455D01*
X484485Y-314720D01*
X484329Y-313985D01*
X483859Y-313355D01*
X483154Y-313040D01*
X482370D01*
X481900Y-312830D01*
X481509Y-312305D01*
X481352Y-311570D01*
X481587Y-310835D01*
X482135Y-310310D01*
X482762Y-310100D01*
X483389Y-310310D01*
X483937Y-310835D01*
X484172Y-311570D01*
X484015Y-312305D01*
X483624Y-312830D01*
X483154Y-313040D01*
X482370D01*
X481665Y-313355D01*
X481195Y-313985D01*
X481039Y-314720D01*
X481195Y-315455D01*
X481587Y-315980D01*
X482214Y-316295D01*
X482762Y-316400D01*
G01X489062D02*
X489610Y-316295D01*
X490237Y-315980D01*
X490629Y-315455D01*
X490785Y-314720D01*
X490629Y-313985D01*
X490159Y-313355D01*
X489454Y-313040D01*
X488670D01*
X488200Y-312830D01*
X487809Y-312305D01*
X487652Y-311570D01*
X487887Y-310835D01*
X488435Y-310310D01*
X489062Y-310100D01*
X489689Y-310310D01*
X490237Y-310835D01*
X490472Y-311570D01*
X490315Y-312305D01*
X489924Y-312830D01*
X489454Y-313040D01*
X488670D01*
X487965Y-313355D01*
X487495Y-313985D01*
X487339Y-314720D01*
X487495Y-315455D01*
X487887Y-315980D01*
X488514Y-316295D01*
X489062Y-316400D01*
G01X495205Y-317555D02*
X495519Y-316190D01*
G01X499312Y-310100D02*
X500409Y-316400D01*
X501662Y-310100D01*
X502915Y-316400D01*
X504012Y-310100D01*
G01X509529Y-316400D02*
X506395D01*
Y-310100D01*
X509529D01*
G01X508275Y-313145D02*
X506395D01*
G01X512460Y-316400D02*
Y-310100D01*
X516064Y-316400D01*
Y-310100D01*
G01X525217Y-316400D02*
Y-310100D01*
G01X528507D02*
Y-316400D01*
G01Y-313250D02*
X525217D01*
G01X530812Y-310100D02*
X531909Y-316400D01*
X533162Y-310100D01*
X534415Y-316400D01*
X535512Y-310100D01*
G01X537504Y-316400D02*
X539462Y-310100D01*
X541420Y-316400D01*
G01X540715Y-314195D02*
X538209D01*
G01X550574Y-311150D02*
X551044Y-310520D01*
X551592Y-310205D01*
X552219Y-310100D01*
X553002Y-310310D01*
X553550Y-310835D01*
X553707Y-311465D01*
X553629Y-312095D01*
X553315Y-312620D01*
X551749Y-313670D01*
X551044Y-314405D01*
X550574Y-315455D01*
X550417Y-316400D01*
X553707D01*
G01X556560D02*
Y-310100D01*
X560164Y-316400D01*
Y-310100D01*
G01X562939Y-316400D02*
Y-310100D01*
X564505D01*
X565132Y-310415D01*
X565602Y-310835D01*
X565994Y-311465D01*
X566307Y-312200D01*
X566385Y-313250D01*
X566307Y-314300D01*
X565994Y-315035D01*
X565602Y-315665D01*
X565132Y-316085D01*
X564505Y-316400D01*
X562939D01*
G01X575695D02*
Y-310100D01*
X577654D01*
X578280Y-310415D01*
X578672Y-310835D01*
X578829Y-311675D01*
X578672Y-312515D01*
X578202Y-313040D01*
X577654Y-313355D01*
X575695D01*
G01X577654D02*
X578829Y-316400D01*
G01X581839D02*
Y-310100D01*
X583405D01*
X584032Y-310415D01*
X584502Y-310835D01*
X584894Y-311465D01*
X585207Y-312200D01*
X585285Y-313250D01*
X585207Y-314300D01*
X584894Y-315035D01*
X584502Y-315665D01*
X584032Y-316085D01*
X583405Y-316400D01*
X581839D01*
G01X589862Y-316610D02*
X589705Y-316505D01*
Y-316295D01*
X589862Y-316190D01*
X590019Y-316295D01*
Y-316505D01*
X589862Y-316610D01*
G01X479862Y-303700D02*
X477342Y-303283D01*
X475137Y-301617D01*
X473247Y-299117D01*
X471987Y-296200D01*
X471357Y-292867D01*
Y-289533D01*
X471987Y-286200D01*
X473247Y-283283D01*
X475137Y-280784D01*
X477342Y-279117D01*
X479862Y-278700D01*
X482382Y-279117D01*
X484587Y-280784D01*
X486477Y-283283D01*
X487737Y-286200D01*
X488367Y-289533D01*
Y-292867D01*
X487737Y-296200D01*
X486477Y-299117D01*
X484587Y-301617D01*
X482382Y-303283D01*
X479862Y-303700D01*
G01X482382Y-297033D02*
X486162Y-303700D01*
G01X499707Y-287034D02*
Y-298700D01*
X500967Y-301617D01*
X502857Y-303283D01*
X505062Y-303700D01*
X507267Y-303283D01*
X509157Y-301617D01*
X510417Y-298700D01*
G01Y-303700D02*
Y-287034D01*
G01X535932Y-303700D02*
Y-287034D01*
G01Y-289950D02*
X534672Y-288284D01*
X532782Y-287450D01*
X530577Y-287034D01*
X528372Y-287867D01*
X526482Y-289533D01*
X525222Y-292034D01*
X524592Y-295367D01*
X525222Y-298700D01*
X526482Y-301201D01*
X528372Y-302867D01*
X530577Y-303700D01*
X532782Y-303283D01*
X534672Y-302034D01*
X535932Y-300367D01*
G01X550107Y-303700D02*
Y-287034D01*
G01Y-291200D02*
X551367Y-289117D01*
X553257Y-287450D01*
X555777Y-287034D01*
X557982Y-287450D01*
X559872Y-289117D01*
X560817Y-292034D01*
Y-303700D01*
G01X580662Y-278700D02*
Y-303700D01*
G01X576252Y-287034D02*
X585072D01*
G01X611532Y-303700D02*
Y-287034D01*
G01Y-289950D02*
X610272Y-288284D01*
X608382Y-287450D01*
X606177Y-287034D01*
X603972Y-287867D01*
X602082Y-289533D01*
X600822Y-292034D01*
X600192Y-295367D01*
X600822Y-298700D01*
X602082Y-301201D01*
X603972Y-302867D01*
X606177Y-303700D01*
X608382Y-303283D01*
X610272Y-302034D01*
X611532Y-300367D01*
G01X651212Y-283400D02*
Y-291400D01*
X655212D01*
G01X663012D02*
Y-286067D01*
G01Y-287000D02*
X662612Y-286467D01*
X662012Y-286200D01*
X661312Y-286067D01*
X660612Y-286333D01*
X660012Y-286867D01*
X659612Y-287667D01*
X659412Y-288733D01*
X659612Y-289800D01*
X660012Y-290600D01*
X660612Y-291133D01*
X661312Y-291400D01*
X662012Y-291267D01*
X662612Y-290867D01*
X663012Y-290334D01*
G01X667112Y-293800D02*
X667712Y-294067D01*
X668512Y-293800D01*
X669012Y-293267D01*
X669412Y-292600D01*
X670012Y-290467D01*
X671312Y-286067D01*
G01X668112D02*
X670012Y-290467D01*
G01X675712Y-287800D02*
X678912D01*
X678612Y-286867D01*
X678112Y-286333D01*
X677412Y-286067D01*
X676712Y-286200D01*
X676112Y-286600D01*
X675712Y-287533D01*
X675512Y-288334D01*
Y-289133D01*
X675712Y-289933D01*
X676212Y-290733D01*
X676812Y-291267D01*
X677512Y-291400D01*
X678212Y-291133D01*
X678912Y-290334D01*
G01X683812Y-291400D02*
Y-286067D01*
G01Y-287133D02*
X684312Y-286600D01*
X684812Y-286200D01*
X685512Y-286067D01*
X686012Y-286200D01*
X686612Y-286600D01*
G01X673512Y-333400D02*
X675912D01*
G01X674712D02*
Y-341400D01*
G01X673512D02*
X675912D01*
G01X681312D02*
Y-336067D01*
G01Y-337133D02*
X681812Y-336600D01*
X682312Y-336200D01*
X683012Y-336067D01*
X683512Y-336200D01*
X684112Y-336600D01*
G01X689212Y-337800D02*
X692412D01*
X692112Y-336867D01*
X691612Y-336333D01*
X690912Y-336067D01*
X690212Y-336200D01*
X689612Y-336600D01*
X689212Y-337533D01*
X689012Y-338334D01*
Y-339133D01*
X689212Y-339933D01*
X689712Y-340733D01*
X690312Y-341267D01*
X691012Y-341400D01*
X691712Y-341133D01*
X692412Y-340334D01*
G01X697012Y-341400D02*
Y-336067D01*
G01Y-337400D02*
X697412Y-336733D01*
X698012Y-336200D01*
X698812Y-336067D01*
X699512Y-336200D01*
X700112Y-336733D01*
X700412Y-337667D01*
Y-341400D01*
G01X705212Y-337800D02*
X708412D01*
X708112Y-336867D01*
X707612Y-336333D01*
X706912Y-336067D01*
X706212Y-336200D01*
X705612Y-336600D01*
X705212Y-337533D01*
X705012Y-338334D01*
Y-339133D01*
X705212Y-339933D01*
X705712Y-340733D01*
X706312Y-341267D01*
X707012Y-341400D01*
X707712Y-341133D01*
X708412Y-340334D01*
G01X684712Y-308400D02*
Y-316400D01*
G01X682412Y-308400D02*
X687012D01*
G01X692712Y-316400D02*
X691912Y-316267D01*
X691212Y-315733D01*
X690612Y-314933D01*
X690212Y-314000D01*
X690012Y-312933D01*
Y-311867D01*
X690212Y-310800D01*
X690612Y-309867D01*
X691212Y-309067D01*
X691912Y-308533D01*
X692712Y-308400D01*
X693512Y-308533D01*
X694212Y-309067D01*
X694812Y-309867D01*
X695212Y-310800D01*
X695412Y-311867D01*
Y-312933D01*
X695212Y-314000D01*
X694812Y-314933D01*
X694212Y-315733D01*
X693512Y-316267D01*
X692712Y-316400D01*
G01X698712D02*
Y-308400D01*
X701112D01*
X701912Y-308800D01*
X702512Y-309733D01*
X702712Y-310800D01*
X702512Y-311867D01*
X702012Y-312667D01*
X701112Y-313067D01*
X698712D01*
G01X704712Y-291400D02*
Y-283400D01*
X703512Y-285000D01*
G01Y-291400D02*
X705912D01*
G01X777812Y-334733D02*
X778412Y-333933D01*
X779112Y-333533D01*
X779912Y-333400D01*
X780912Y-333667D01*
X781612Y-334333D01*
X781812Y-335133D01*
X781712Y-335934D01*
X781312Y-336600D01*
X779312Y-337933D01*
X778412Y-338867D01*
X777812Y-340200D01*
X777612Y-341400D01*
X781812D01*
G01X787712Y-333400D02*
X786912Y-333667D01*
X786312Y-334333D01*
X785912Y-335133D01*
X785612Y-336200D01*
X785512Y-337400D01*
X785612Y-338600D01*
X785912Y-339667D01*
X786312Y-340467D01*
X786912Y-341133D01*
X787712Y-341400D01*
X788512Y-341133D01*
X789112Y-340467D01*
X789512Y-339667D01*
X789812Y-338600D01*
X789912Y-337400D01*
X789812Y-336200D01*
X789512Y-335133D01*
X789112Y-334333D01*
X788512Y-333667D01*
X787712Y-333400D01*
G01X795712Y-341400D02*
Y-333400D01*
X794512Y-335000D01*
G01Y-341400D02*
X796912D01*
G01X801812Y-334733D02*
X802412Y-333933D01*
X803112Y-333533D01*
X803912Y-333400D01*
X804912Y-333667D01*
X805612Y-334333D01*
X805812Y-335133D01*
X805712Y-335934D01*
X805312Y-336600D01*
X803312Y-337933D01*
X802412Y-338867D01*
X801812Y-340200D01*
X801612Y-341400D01*
X805812D01*
G01X809912Y-341667D02*
X813512Y-333400D01*
G01X819712Y-341400D02*
Y-333400D01*
X818512Y-335000D01*
G01Y-341400D02*
X820912D01*
G01X827712Y-333400D02*
X826912Y-333667D01*
X826312Y-334333D01*
X825912Y-335133D01*
X825612Y-336200D01*
X825512Y-337400D01*
X825612Y-338600D01*
X825912Y-339667D01*
X826312Y-340467D01*
X826912Y-341133D01*
X827712Y-341400D01*
X828512Y-341133D01*
X829112Y-340467D01*
X829512Y-339667D01*
X829812Y-338600D01*
X829912Y-337400D01*
X829812Y-336200D01*
X829512Y-335133D01*
X829112Y-334333D01*
X828512Y-333667D01*
X827712Y-333400D01*
G01X833912Y-341667D02*
X837512Y-333400D01*
G01X841512Y-339800D02*
X842112Y-340733D01*
X842912Y-341267D01*
X843812Y-341400D01*
X844612Y-341267D01*
X845412Y-340600D01*
X845912Y-339800D01*
X846012Y-339000D01*
X845812Y-338067D01*
X845112Y-337400D01*
X844412Y-337133D01*
X843512D01*
G01X844412D02*
X845012Y-336733D01*
X845512Y-336067D01*
X845712Y-335267D01*
X845512Y-334467D01*
X845012Y-333800D01*
X844112Y-333400D01*
X843212Y-333533D01*
X842312Y-334067D01*
G01X851712Y-341400D02*
Y-333400D01*
X850512Y-335000D01*
G01Y-341400D02*
X852912D01*
G01X777512Y-316400D02*
Y-308400D01*
X779512D01*
X780312Y-308800D01*
X780912Y-309333D01*
X781412Y-310133D01*
X781812Y-311067D01*
X781912Y-312400D01*
X781812Y-313733D01*
X781412Y-314667D01*
X780912Y-315467D01*
X780312Y-316000D01*
X779512Y-316400D01*
X777512D01*
G01X785212D02*
X787712Y-308400D01*
X790212Y-316400D01*
G01X789312Y-313600D02*
X786112D01*
G01X795712Y-308400D02*
X794912Y-308667D01*
X794312Y-309333D01*
X793912Y-310133D01*
X793612Y-311200D01*
X793512Y-312400D01*
X793612Y-313600D01*
X793912Y-314667D01*
X794312Y-315467D01*
X794912Y-316133D01*
X795712Y-316400D01*
X796512Y-316133D01*
X797112Y-315467D01*
X797512Y-314667D01*
X797812Y-313600D01*
X797912Y-312400D01*
X797812Y-311200D01*
X797512Y-310133D01*
X797112Y-309333D01*
X796512Y-308667D01*
X795712Y-308400D01*
G01X803712D02*
Y-316400D01*
G01X801412Y-308400D02*
X806012D01*
G01X809812Y-313067D02*
X810512Y-312133D01*
X811112Y-311600D01*
X811912Y-311333D01*
X812612Y-311600D01*
X813112Y-312133D01*
X813512Y-312933D01*
X813612Y-313867D01*
X813512Y-314667D01*
X813112Y-315467D01*
X812512Y-316133D01*
X811812Y-316400D01*
X811012Y-316133D01*
X810312Y-315334D01*
X809912Y-314133D01*
X809812Y-312800D01*
X810012Y-311067D01*
X810312Y-310133D01*
X810812Y-309200D01*
X811512Y-308533D01*
X812212Y-308400D01*
X812912Y-308667D01*
X813412Y-309333D01*
G01X817112Y-316400D02*
Y-308400D01*
X819712Y-315067D01*
X822312Y-308400D01*
Y-316400D01*
G01X827712Y-308400D02*
Y-316400D01*
G01X825412Y-308400D02*
X830012D01*
G01X833612Y-316400D02*
Y-308400D01*
G01X837812D02*
Y-316400D01*
G01Y-312400D02*
X833612D01*
G01X843712Y-316400D02*
X844412Y-316267D01*
X845212Y-315867D01*
X845712Y-315200D01*
X845912Y-314267D01*
X845712Y-313334D01*
X845112Y-312533D01*
X844212Y-312133D01*
X843212D01*
X842612Y-311867D01*
X842112Y-311200D01*
X841912Y-310267D01*
X842212Y-309333D01*
X842912Y-308667D01*
X843712Y-308400D01*
X844512Y-308667D01*
X845212Y-309333D01*
X845512Y-310267D01*
X845312Y-311200D01*
X844812Y-311867D01*
X844212Y-312133D01*
X843212D01*
X842312Y-312533D01*
X841712Y-313334D01*
X841512Y-314267D01*
X841712Y-315200D01*
X842212Y-315867D01*
X843012Y-316267D01*
X843712Y-316400D01*
G01X853912Y-309067D02*
X853312Y-308667D01*
X852612Y-308400D01*
X851812D01*
X850912Y-308800D01*
X850212Y-309467D01*
X849712Y-310267D01*
X849312Y-311600D01*
X849212Y-312800D01*
X849412Y-314000D01*
X849712Y-314800D01*
X850312Y-315600D01*
X851012Y-316133D01*
X851712Y-316400D01*
X852412D01*
X853112Y-316133D01*
X853712Y-315733D01*
X854212Y-315200D01*
G01X859712Y-308400D02*
X858912Y-308667D01*
X858312Y-309333D01*
X857912Y-310133D01*
X857612Y-311200D01*
X857512Y-312400D01*
X857612Y-313600D01*
X857912Y-314667D01*
X858312Y-315467D01*
X858912Y-316133D01*
X859712Y-316400D01*
X860512Y-316133D01*
X861112Y-315467D01*
X861512Y-314667D01*
X861812Y-313600D01*
X861912Y-312400D01*
X861812Y-311200D01*
X861512Y-310133D01*
X861112Y-309333D01*
X860512Y-308667D01*
X859712Y-308400D01*
G01X799712Y-283400D02*
Y-291400D01*
G01X797412Y-283400D02*
X802012D01*
G01X805812Y-288067D02*
X806512Y-287133D01*
X807112Y-286600D01*
X807912Y-286333D01*
X808612Y-286600D01*
X809112Y-287133D01*
X809512Y-287933D01*
X809612Y-288867D01*
X809512Y-289667D01*
X809112Y-290467D01*
X808512Y-291133D01*
X807812Y-291400D01*
X807012Y-291133D01*
X806312Y-290334D01*
X805912Y-289133D01*
X805812Y-287800D01*
X806012Y-286067D01*
X806312Y-285133D01*
X806812Y-284200D01*
X807512Y-283533D01*
X808212Y-283400D01*
X808912Y-283667D01*
X809412Y-284333D01*
G01X813112Y-291400D02*
Y-283400D01*
X815712Y-290067D01*
X818312Y-283400D01*
Y-291400D01*
G01X820712Y-294067D02*
X826712D01*
G01X831712Y-283400D02*
Y-291400D01*
G01X829412Y-283400D02*
X834012D01*
G01X838312Y-291400D02*
Y-286067D01*
G01Y-287133D02*
X838812Y-286600D01*
X839312Y-286200D01*
X840012Y-286067D01*
X840512Y-286200D01*
X841112Y-286600D01*
G01X849512Y-291400D02*
Y-286067D01*
G01Y-287000D02*
X849112Y-286467D01*
X848512Y-286200D01*
X847812Y-286067D01*
X847112Y-286333D01*
X846512Y-286867D01*
X846112Y-287667D01*
X845912Y-288733D01*
X846112Y-289800D01*
X846512Y-290600D01*
X847112Y-291133D01*
X847812Y-291400D01*
X848512Y-291267D01*
X849112Y-290867D01*
X849512Y-290334D01*
G01X853612Y-293800D02*
X854212Y-294067D01*
X855012Y-293800D01*
X855512Y-293267D01*
X855912Y-292600D01*
X856512Y-290467D01*
X857812Y-286067D01*
G01X854612D02*
X856512Y-290467D01*
G01X860712Y-294067D02*
X866712D01*
G01X872512Y-287133D02*
X872912Y-286733D01*
X873212Y-286067D01*
X873412Y-285133D01*
X873212Y-284333D01*
X872812Y-283800D01*
X872112Y-283400D01*
X869412D01*
Y-291400D01*
X872712D01*
X873412Y-290867D01*
X873812Y-290067D01*
X874012Y-289133D01*
X873812Y-288200D01*
X873212Y-287400D01*
X872512Y-287133D01*
X869412D01*
G01X877712Y-291400D02*
Y-283400D01*
X880112D01*
X880912Y-283800D01*
X881512Y-284733D01*
X881712Y-285800D01*
X881512Y-286867D01*
X881012Y-287667D01*
X880112Y-288067D01*
X877712D01*
G01X896912Y-334067D02*
X896312Y-333667D01*
X895612Y-333400D01*
X894812D01*
X893912Y-333800D01*
X893212Y-334467D01*
X892712Y-335267D01*
X892312Y-336600D01*
X892212Y-337800D01*
X892412Y-339000D01*
X892712Y-339800D01*
X893312Y-340600D01*
X894012Y-341133D01*
X894712Y-341400D01*
X895412D01*
X896112Y-341133D01*
X896712Y-340733D01*
X897212Y-340200D01*
G01X922212Y-341400D02*
Y-333400D01*
X921012Y-335000D01*
G01Y-341400D02*
X923412D01*
G01X928312Y-338067D02*
X929012Y-337133D01*
X929612Y-336600D01*
X930412Y-336333D01*
X931112Y-336600D01*
X931612Y-337133D01*
X932012Y-337933D01*
X932112Y-338867D01*
X932012Y-339667D01*
X931612Y-340467D01*
X931012Y-341133D01*
X930312Y-341400D01*
X929512Y-341133D01*
X928812Y-340334D01*
X928412Y-339133D01*
X928312Y-337800D01*
X928512Y-336067D01*
X928812Y-335133D01*
X929312Y-334200D01*
X930012Y-333533D01*
X930712Y-333400D01*
X931412Y-333667D01*
X931912Y-334333D01*
G54D27*
X332000Y128960D03*
Y136440D03*
X340473Y129060D03*
Y136540D03*
X617949Y131360D03*
Y138840D03*
X626173Y131360D03*
Y138840D03*
X1206000Y128760D03*
Y136240D03*
X1214100Y128860D03*
Y136340D03*
X1495800Y135760D03*
Y143240D03*
X1487600Y135760D03*
Y143240D03*
G54D36*
X398307Y40511D03*
X396732Y72795D03*
X417205Y40511D03*
X407756D03*
X414055D03*
X410906D03*
X420354D03*
X401457D03*
X404606D03*
X421929Y72795D03*
X418780D03*
X399882D03*
X406181D03*
X415630D03*
X412480D03*
X409331D03*
X403032D03*
X426654Y40511D03*
X423504D03*
X425079Y72795D03*
X557048Y40512D03*
X547599D03*
X560198D03*
X550749D03*
X553898D03*
X546024Y72796D03*
X549174D03*
X555473D03*
X558623D03*
X552324D03*
X575946Y40512D03*
X566497D03*
X563347D03*
X572796D03*
X569646D03*
X574371Y72796D03*
X571221D03*
X568072D03*
X564922D03*
X561772D03*
X1268386Y40512D03*
X1271536D03*
X1274685D03*
X1266811Y72796D03*
X1269961D03*
X1273111D03*
X1296733Y40512D03*
X1287284D03*
X1277835D03*
X1284134D03*
X1280985D03*
X1293583D03*
X1290433D03*
X1295158Y72796D03*
X1292008D03*
X1288859D03*
X1276260D03*
X1285709D03*
X1282559D03*
X1279410D03*
X1427127Y40511D03*
X1417678D03*
X1433426D03*
X1430277D03*
X1420828D03*
X1423977D03*
X1416103Y72795D03*
X1419253D03*
X1425552D03*
X1435001D03*
X1431851D03*
X1428702D03*
X1422403D03*
X1446025Y40511D03*
X1436576D03*
X1442875D03*
X1439725D03*
X1444450Y72795D03*
X1441300D03*
X1438151D03*
G54D18*
X56339Y135827D03*
G54D45*
X503859Y151650D03*
X1373938D03*
G54D55*
G01X686162Y101968D02*
Y97673D01*
X685477Y96988D01*
Y73205D01*
G02X684891Y71791I-1999J0D01*
G01X682386Y69286D01*
G02X680972Y68700I-1414J1413D01*
G01X676052D01*
G03X675110Y68310I0J-1333D01*
G02X674168Y67920I-942J943D01*
G01X662618D01*
X660920Y69618D01*
Y71290D01*
X659310Y72900D01*
G01X683012Y101968D02*
Y97673D01*
X684097Y96588D01*
Y73205D01*
G02X683915Y72767I-618J0D01*
G01X681410Y70262D01*
G02X680972Y70080I-438J436D01*
G01X676052D01*
G03X674148Y69300I0J-2714D01*
G01X663190D01*
X662300Y70190D01*
Y70890D01*
X664310Y72900D01*
G01X654400Y92100D02*
X656120Y93820D01*
X664720D01*
X666379Y95479D01*
Y96788D01*
X667264Y97673D01*
Y101968D01*
G01X654400Y97100D02*
X656300Y95200D01*
X664148D01*
X664999Y96051D01*
Y96788D01*
X664114Y97673D01*
Y101968D01*
G01X672638Y93290D02*
X674548Y95200D01*
Y96888D01*
X673563Y97873D01*
Y101968D01*
G01X671988Y111850D02*
Y116145D01*
X672873Y117030D01*
Y124120D01*
X671063Y125930D01*
G01X675138Y111850D02*
Y116145D01*
X674253Y117030D01*
Y124120D01*
X676063Y125930D01*
G01X665689Y111850D02*
Y116145D01*
X664804Y117030D01*
Y119190D01*
X666614Y121000D01*
G01X662540Y111850D02*
Y116146D01*
X663424Y117030D01*
Y119190D01*
X661614Y121000D01*
G01X695610Y101968D02*
Y97673D01*
X694725Y96788D01*
Y96088D01*
X695613Y95200D01*
X699770D01*
X701670Y97100D01*
G01X692461Y101968D02*
Y97672D01*
X693345Y96788D01*
Y95516D01*
X695041Y93820D01*
X699950D01*
X701670Y92100D01*
G01X677638Y93290D02*
X675928Y95000D01*
Y96888D01*
X676713Y97673D01*
Y101968D01*
G01X689961Y122030D02*
X691771Y120220D01*
Y117030D01*
X690886Y116145D01*
Y111850D01*
G01X694961Y122030D02*
X693151Y120220D01*
Y117030D01*
X694036Y116145D01*
Y111850D01*
G01X681437D02*
Y116145D01*
X682322Y117030D01*
Y127890D01*
X680612Y129600D01*
G01X684587Y111850D02*
Y116145D01*
X683702Y117030D01*
Y127690D01*
X685612Y129600D01*
G01X724400Y105600D02*
X726220Y103780D01*
Y98180D01*
X732300Y92100D01*
X739000D01*
X741221Y94321D01*
Y96788D01*
X742106Y97673D01*
Y101968D01*
G01X729400Y105600D02*
X727600Y103800D01*
Y98752D01*
X732872Y93480D01*
X738428D01*
X739841Y94893D01*
Y96788D01*
X738956Y97673D01*
Y101968D01*
G01X730310Y115390D02*
X728500Y117200D01*
Y118100D01*
X729500Y119100D01*
X737400D01*
X738366Y118134D01*
Y117130D01*
X737382Y116146D01*
Y111850D01*
G01X725310Y115390D02*
X727120Y117200D01*
Y118672D01*
X728928Y120480D01*
X737972D01*
X739746Y118706D01*
Y116930D01*
X740531Y116145D01*
Y111850D01*
G01X761929Y72900D02*
X760119Y74710D01*
Y97488D01*
X761004Y98373D01*
Y101968D01*
G01X756929Y72900D02*
X758739Y74710D01*
Y97488D01*
X757854Y98373D01*
Y101968D01*
G01X751555D02*
Y97673D01*
X750670Y96788D01*
Y94640D01*
X752480Y92830D01*
G01X748405Y101968D02*
Y97673D01*
X749290Y96788D01*
Y94640D01*
X747480Y92830D01*
G01X767303Y101968D02*
Y97672D01*
X768187Y96788D01*
Y95516D01*
X769803Y93900D01*
X776430D01*
X778200Y92130D01*
G01X745905Y120452D02*
X747715Y118642D01*
Y117030D01*
X746830Y116145D01*
Y111850D01*
G01X750905Y120452D02*
X749095Y118642D01*
Y117030D01*
X749980Y116145D01*
Y111850D01*
G01X764803Y120330D02*
X766541Y118592D01*
Y116934D01*
X765728Y116121D01*
Y111850D01*
G01X760410Y124730D02*
X758600Y122920D01*
Y116974D01*
X759429Y116145D01*
Y111850D01*
G01X755410Y124730D02*
X757220Y122920D01*
Y117086D01*
X756279Y116145D01*
Y111850D01*
G01X770452Y101968D02*
Y97673D01*
X769567Y96788D01*
Y96088D01*
X770375Y95280D01*
X776350D01*
X778200Y97130D01*
G01X769803Y120330D02*
X767921Y118448D01*
Y117078D01*
X768878Y116121D01*
Y111850D01*
G01X1524478Y97100D02*
X1526378Y95200D01*
X1534226D01*
X1535077Y96051D01*
Y96788D01*
X1534192Y97673D01*
Y101968D01*
G01X1524478Y92100D02*
X1526198Y93820D01*
X1534798D01*
X1536457Y95479D01*
Y96788D01*
X1537342Y97673D01*
Y101968D01*
G01X1534388Y72900D02*
X1532378Y70890D01*
Y70190D01*
X1533268Y69300D01*
X1544592D01*
G03X1545030Y69482I0J618D01*
G01X1545038Y69490D01*
G02X1547428Y70480I2390J-2390D01*
G01X1550272D01*
G03X1550710Y70662I0J618D01*
G01X1553793Y73745D01*
G03X1553975Y74183I-436J438D01*
G01Y96788D01*
X1553090Y97673D01*
Y101968D01*
G01X1529388Y72900D02*
X1530998Y71290D01*
Y69618D01*
X1532696Y67920D01*
X1544592D01*
G03X1546006Y68506I0J1999D01*
G01X1546014Y68514D01*
G02X1547428Y69100I1414J-1413D01*
G01X1550272D01*
G03X1551686Y69686I0J1999D01*
G01X1554769Y72769D01*
G03X1555355Y74183I-1413J1414D01*
G01Y96788D01*
X1556240Y97673D01*
Y101968D01*
G01X1542716Y93290D02*
X1544626Y95200D01*
Y96888D01*
X1543641Y97873D01*
Y101968D01*
G01X1546791D02*
Y97673D01*
X1546006Y96888D01*
Y95000D01*
X1547716Y93290D01*
G01X1532618Y111850D02*
Y116146D01*
X1533502Y117030D01*
Y119190D01*
X1531692Y121000D01*
G01X1545216Y111850D02*
Y116145D01*
X1544331Y117030D01*
Y124120D01*
X1546141Y125930D01*
G01X1542066Y111850D02*
Y116145D01*
X1542951Y117030D01*
Y124120D01*
X1541141Y125930D01*
G01X1535767Y111850D02*
Y116145D01*
X1534882Y117030D01*
Y119190D01*
X1536692Y121000D01*
G01X1562539Y101968D02*
Y97672D01*
X1563423Y96788D01*
Y95516D01*
X1565119Y93820D01*
X1570028D01*
X1571748Y92100D01*
G01X1565688Y101968D02*
Y97673D01*
X1564803Y96788D01*
Y96088D01*
X1565691Y95200D01*
X1569848D01*
X1571748Y97100D01*
G01X1554665Y111850D02*
Y116145D01*
X1553780Y117030D01*
Y127690D01*
X1555690Y129600D01*
G01X1551515Y111850D02*
Y116145D01*
X1552400Y117030D01*
Y127890D01*
X1550690Y129600D01*
G01X1565039Y122030D02*
X1563229Y120220D01*
Y117030D01*
X1564114Y116145D01*
Y111850D01*
G01X1560039Y122030D02*
X1561849Y120220D01*
Y117030D01*
X1560964Y116145D01*
Y111850D01*
G01X1612185Y101968D02*
Y97674D01*
X1611299Y96788D01*
Y94321D01*
X1609078Y92100D01*
X1602378D01*
X1596298Y98180D01*
Y103780D01*
X1594478Y105600D01*
G01X1610610Y111850D02*
Y116144D01*
X1609824Y116930D01*
Y118706D01*
X1608050Y120480D01*
X1599006D01*
X1597198Y118672D01*
Y117200D01*
X1595388Y115390D01*
G01X1609035Y101968D02*
Y97672D01*
X1609919Y96788D01*
Y94893D01*
X1608506Y93480D01*
X1602950D01*
X1597678Y98752D01*
Y103800D01*
X1599478Y105600D01*
G01X1618484Y101968D02*
Y97672D01*
X1619368Y96788D01*
Y94640D01*
X1617558Y92830D01*
G01X1620059Y111850D02*
Y116144D01*
X1619173Y117030D01*
Y118642D01*
X1620983Y120452D01*
G01X1607461Y111850D02*
Y116147D01*
X1608444Y117130D01*
Y118134D01*
X1607478Y119100D01*
X1599578D01*
X1598578Y118100D01*
Y117200D01*
X1600388Y115390D01*
G01X1616909Y111850D02*
Y116146D01*
X1617793Y117030D01*
Y118642D01*
X1615983Y120452D01*
G01X1627933Y101968D02*
X1627932Y101967D01*
Y98373D01*
X1628817Y97488D01*
Y74710D01*
X1627007Y72900D01*
G01X1631083Y101968D02*
Y98374D01*
X1630197Y97488D01*
Y74710D01*
X1632007Y72900D01*
G01X1640531Y101968D02*
Y97674D01*
X1639645Y96788D01*
Y96088D01*
X1640453Y95280D01*
X1646428D01*
X1648278Y97130D01*
G01X1621634Y101968D02*
Y97674D01*
X1620748Y96788D01*
Y94640D01*
X1622558Y92830D01*
G01X1637382Y101968D02*
Y97671D01*
X1638265Y96788D01*
Y95516D01*
X1639881Y93900D01*
X1646508D01*
X1648278Y92130D01*
G01X1625488Y124730D02*
X1627298Y122920D01*
Y117086D01*
X1626358Y116146D01*
Y111850D01*
G01X1638957D02*
Y116120D01*
X1637999Y117078D01*
Y118448D01*
X1639881Y120330D01*
G01X1630488Y124730D02*
X1628678Y122920D01*
Y116974D01*
X1629508Y116144D01*
Y111850D01*
G01X1635807D02*
Y116122D01*
X1636619Y116934D01*
Y118592D01*
X1634881Y120330D01*
G54D46*
X639283Y108622D03*
Y167677D03*
X793693Y108622D03*
Y167677D03*
X1509362Y108622D03*
Y167677D03*
X1663772Y108622D03*
Y167677D03*
G54D28*
X343780Y11810D03*
Y19684D03*
Y27558D03*
X335906Y11810D03*
Y19684D03*
Y27558D03*
X343780Y43306D03*
Y51180D03*
X335906Y43306D03*
Y51180D03*
X343780Y59054D03*
X367402Y11810D03*
Y19684D03*
Y27558D03*
X359528Y11810D03*
Y19684D03*
Y27558D03*
X367402Y43306D03*
Y51180D03*
X359528Y43306D03*
Y51180D03*
X367402Y59054D03*
X359528D03*
X1205984Y11810D03*
Y19684D03*
Y27558D03*
Y43306D03*
Y51180D03*
X1213858Y11810D03*
Y19684D03*
Y27558D03*
X1229606Y11810D03*
Y19684D03*
Y27558D03*
Y43306D03*
Y51180D03*
X1213858Y43306D03*
Y51180D03*
X1229606Y59054D03*
X1213858D03*
X1237480Y11810D03*
Y19684D03*
Y27558D03*
Y43306D03*
Y51180D03*
Y59054D03*
G54D37*
X383642Y40532D03*
Y79902D03*
X396122Y99587D03*
X383642Y119272D03*
Y158642D03*
X417382Y99587D03*
X405964Y178327D03*
X439744Y99587D03*
Y138957D03*
Y178327D03*
X532934Y40532D03*
Y79902D03*
Y119272D03*
Y158642D03*
X545414Y99587D03*
X555256Y178327D03*
X566674Y99587D03*
X589036D03*
Y138957D03*
Y178327D03*
X1253721Y40532D03*
Y79902D03*
Y119272D03*
Y158642D03*
X1266201Y99587D03*
X1276043Y178327D03*
X1287461Y99587D03*
X1309823D03*
Y138957D03*
Y178327D03*
X1403012Y40532D03*
Y79902D03*
Y119272D03*
Y158642D03*
X1415492Y99587D03*
X1436752D03*
X1425334Y178327D03*
X1459114Y99587D03*
Y138957D03*
Y178327D03*
G54D19*
X51900Y162300D03*
X53200Y169500D03*
X76900Y20200D03*
X65600Y160400D03*
X57200Y165300D03*
X73200Y162100D03*
X62200Y169900D03*
X70400Y170000D03*
X90200Y22400D03*
X94900Y144500D03*
X83800Y154500D03*
X99000Y148900D03*
X78800Y158000D03*
X93900Y162900D03*
X90200Y169500D03*
X81600Y162600D03*
X92600Y154800D03*
X100700Y163400D03*
X89000Y150200D03*
X88000Y158900D03*
X83500Y169700D03*
X78200Y169900D03*
X96900Y169500D03*
X98000Y157100D03*
X102500Y29400D03*
X107200Y19300D03*
X109400Y41000D03*
X121200Y33900D03*
X123100Y49600D03*
X102000Y141900D03*
X114000Y145200D03*
X119900Y143200D03*
X108600Y143100D03*
X111800Y151800D03*
X104900Y157400D03*
X120500Y157200D03*
X111900Y164800D03*
X118100Y162100D03*
X104500Y150300D03*
X110900Y159200D03*
X118400Y152000D03*
X106500Y170300D03*
X115300Y170200D03*
X143300Y27300D03*
X123900Y41000D03*
X143800Y53600D03*
X144500Y40000D03*
X138700Y63500D03*
X144100Y72900D03*
X133100Y71300D03*
X139800Y90200D03*
X131400Y91300D03*
X144200Y96300D03*
X129200Y101300D03*
X143000Y105700D03*
X129200Y142400D03*
X126600Y149500D03*
X141900Y154700D03*
X134800Y164000D03*
X144700Y149200D03*
X137100Y158600D03*
X137000Y170400D03*
X127400D03*
X165600Y19400D03*
X150300Y20200D03*
X168100Y48400D03*
X151500Y35800D03*
X166500Y34700D03*
X153100Y49600D03*
X159800Y65100D03*
X161800Y86800D03*
X148800Y85000D03*
X158200Y102400D03*
X163500Y144900D03*
X150300Y144600D03*
X156000Y138200D03*
X156500Y144800D03*
X169900Y146800D03*
X164400Y138200D03*
X169400Y153600D03*
X155600Y157900D03*
X162100Y164300D03*
X168000Y161200D03*
X149300Y164100D03*
X163200Y151600D03*
X162000Y159400D03*
X148000Y158800D03*
X152600Y152000D03*
X155900Y170000D03*
X163800Y170100D03*
X148600D03*
X180300Y20200D03*
X184100Y36600D03*
X183100Y49600D03*
X174300Y73300D03*
X191700Y75400D03*
X175000Y62300D03*
X181400Y84700D03*
X174200Y96300D03*
X190400Y136600D03*
X191200Y142400D03*
X178100Y144600D03*
X184000Y138800D03*
X173600Y138700D03*
X185800Y145400D03*
X190000Y149800D03*
X179300Y156400D03*
X187100Y155800D03*
X192100Y163500D03*
X176300Y164400D03*
X175500Y151300D03*
X173700Y158700D03*
X190400Y169800D03*
X182600Y152000D03*
X171300Y170000D03*
X177800Y170400D03*
X194400Y20200D03*
X197800Y30900D03*
X210300Y20200D03*
X197800Y48000D03*
X214700Y35800D03*
X213100Y49600D03*
X195600Y64100D03*
X206700Y72700D03*
X209400Y60900D03*
X204200Y96300D03*
X196200Y102300D03*
X211300Y138600D03*
X204200Y139200D03*
X195900Y146300D03*
X213300Y146800D03*
X197300Y139100D03*
X205100Y147700D03*
X201500Y154400D03*
X213500Y155400D03*
X197100Y160800D03*
X194600Y154800D03*
X225800Y19600D03*
X229200Y30900D03*
X227100Y43000D03*
X216400Y100500D03*
X234200Y96300D03*
X225600Y104500D03*
X234500Y138700D03*
X230600Y146400D03*
X218100Y140500D03*
X224400Y138200D03*
X236800Y165000D03*
X238800Y157500D03*
X231600Y155100D03*
X221800Y149400D03*
X236500Y185900D03*
X235400Y172900D03*
X254400Y19200D03*
X240300Y20200D03*
X257800Y51200D03*
X244900Y36600D03*
X243100Y49600D03*
X254400Y74300D03*
X251600Y100100D03*
X248600Y142900D03*
X242600Y140100D03*
X254400Y138200D03*
X252200Y159400D03*
X239600Y148700D03*
X245100Y165200D03*
X255400Y148400D03*
X245600Y157000D03*
X248400Y149800D03*
X252800Y179900D03*
X239800Y178700D03*
X243300Y185600D03*
X242300Y171800D03*
X252600Y192000D03*
X242400Y193300D03*
X270300Y20200D03*
X268300Y36200D03*
X273100Y49600D03*
X283600Y69500D03*
X273300Y94900D03*
X264200Y96300D03*
X281800Y100900D03*
X262900Y104900D03*
X267700Y145200D03*
X284400Y138200D03*
X280000Y159800D03*
X281000Y180700D03*
X265300Y170000D03*
X282600Y192000D03*
X294200Y96300D03*
X307800Y101100D03*
X300300Y140000D03*
X287600Y150000D03*
X292800Y169800D03*
X324200Y96300D03*
X314600Y104100D03*
X310200Y135900D03*
X350000Y161800D03*
X338300Y162900D03*
X350200Y181100D03*
X338300Y183800D03*
X359200Y164900D03*
X359100Y184400D03*
X806800Y26700D03*
X813700Y43900D03*
X810700Y65200D03*
X809700Y86500D03*
X836800Y26700D03*
X825200Y111700D03*
X840700Y65200D03*
X839700Y86500D03*
X855200Y111700D03*
X838300Y128100D03*
X855400Y152400D03*
X857000Y189800D03*
X855400Y173000D03*
X866800Y26700D03*
X870700Y65200D03*
X869700Y86500D03*
X868300Y128100D03*
X896800Y26700D03*
X900700Y65200D03*
X899700Y86500D03*
X885200Y111700D03*
X898300Y128100D03*
X885400Y152400D03*
X887000Y189800D03*
X885400Y173000D03*
X926800Y26700D03*
X929700Y86500D03*
X915200Y111700D03*
X928300Y128100D03*
X915400Y152400D03*
X917000Y189800D03*
X915400Y173000D03*
X930700Y65200D03*
X945200Y111700D03*
X945400Y152400D03*
X947000Y189800D03*
X945400Y173000D03*
X959000Y18000D03*
X956800Y26700D03*
X960700Y65200D03*
X959700Y86500D03*
X975200Y111700D03*
X958300Y128100D03*
X975400Y152400D03*
Y173000D03*
X986800Y26700D03*
X990700Y65200D03*
X989700Y86500D03*
X988300Y128100D03*
X977000Y189800D03*
X1018800Y26300D03*
X1009700Y81500D03*
X1005200Y111700D03*
X1018300Y128100D03*
X1005400Y152400D03*
X1007000Y189800D03*
X1005400Y173000D03*
X1043000Y45500D03*
X1022700Y64800D03*
X1031900Y84100D03*
X1037200Y111300D03*
X1035400Y152400D03*
X1037000Y189800D03*
X1035400Y173000D03*
X1063700Y15300D03*
X1048800Y26300D03*
X1052700Y64800D03*
X1061900Y84100D03*
X1067200Y111300D03*
X1048300Y128100D03*
X1065400Y152400D03*
X1067000Y189800D03*
X1067400Y172600D03*
X1078800Y26300D03*
X1073000Y45500D03*
X1082700Y64800D03*
X1078300Y128100D03*
X1091900Y84100D03*
X1097200Y111300D03*
X1108300Y128100D03*
X1095400Y152400D03*
X1097000Y189800D03*
X1097400Y172600D03*
X1136600Y19700D03*
X1135400Y41000D03*
X1120900Y64500D03*
X1121900Y84100D03*
X1127200Y111300D03*
X1125400Y152400D03*
X1127000Y189800D03*
X1127400Y172600D03*
X1147100Y64500D03*
X1151900Y84100D03*
X1155400Y152400D03*
X1157000Y189800D03*
X1157400Y172600D03*
X1636400Y43200D03*
G54D56*
G01X405531Y21960D02*
X404211Y23280D01*
Y34852D01*
X404606Y35247D01*
Y40511D01*
G01X400531Y21960D02*
X401851Y23280D01*
Y34852D01*
X401457Y35246D01*
Y40511D01*
G01X453480Y36200D02*
X451860Y34580D01*
Y21188D01*
G02X451274Y19774I-1999J0D01*
G01X449886Y18386D01*
G02X448472Y17800I-1414J1413D01*
G01X425968D01*
G02X422885Y19077I0J4360D01*
G01X422026Y19936D01*
G02X420749Y23019I3083J3083D01*
G01Y34852D01*
X420354Y35247D01*
Y40511D01*
G01X447880Y36200D02*
X449500Y34580D01*
Y31728D01*
G02X448914Y30314I-1999J0D01*
G01X448686Y30086D01*
G03X448100Y28672I1413J-1414D01*
G01Y27628D01*
G03X448686Y26214I1999J0D01*
G01X448914Y25986D01*
G02X449500Y24572I-1413J-1414D01*
G01Y21736D01*
G02X449219Y21057I-961J0D01*
G01X448603Y20441D01*
G02X447924Y20160I-679J680D01*
G01X443768D01*
G02X442354Y20746I0J1999D01*
G01X442126Y20974D01*
G03X440712Y21560I-1414J-1413D01*
G01X439488D01*
G03X438074Y20974I0J-1999D01*
G01X437846Y20746D01*
G02X436432Y20160I-1414J1413D01*
G01X435268D01*
G02X433854Y20746I0J1999D01*
G01X433626Y20974D01*
G03X432212Y21560I-1414J-1413D01*
G01X430888D01*
G03X429474Y20974I0J-1999D01*
G01X429246Y20746D01*
G02X427832Y20160I-1414J1413D01*
G01X425968D01*
G02X424554Y20746I0J1999D01*
G01X423695Y21605D01*
G02X423109Y23019I1413J1414D01*
G01Y34852D01*
X423504Y35247D01*
Y40511D01*
G01X523300Y15580D02*
X524620Y16900D01*
X549872D01*
G03X551286Y17486I0J1999D01*
G01X552917Y19117D01*
G03X553503Y20531I-1413J1414D01*
G01Y34853D01*
X553898Y35248D01*
Y40512D01*
G01X523300Y20580D02*
X524034Y19846D01*
G03X525448Y19260I1414J1413D01*
G01X526532D01*
G03X527946Y19846I0J1999D01*
G01X528114Y20014D01*
G02X529528Y20600I1414J-1413D01*
G01X530565D01*
G02X531475Y20223I0J-1287D01*
G01X531852Y19846D01*
G03X533266Y19260I1414J1413D01*
G01X534170D01*
G03X535584Y19846I0J1999D01*
G01X535752Y20014D01*
G02X537166Y20600I1414J-1413D01*
G01X538127D01*
G02X539037Y20223I0J-1287D01*
G01X539414Y19846D01*
G03X540828Y19260I1414J1413D01*
G01X542332D01*
G03X543746Y19846I0J1999D01*
G01X543914Y20014D01*
G02X545328Y20600I1414J-1413D01*
G01X546149D01*
G02X547260Y20140I0J-1572D01*
G01X547721Y19679D01*
G03X548732Y19260I1011J1010D01*
G01X549324D01*
G03X550003Y19541I0J961D01*
G01X550862Y20400D01*
G03X551143Y21079I-680J679D01*
G01Y22793D01*
G03X550557Y24208I-2000J1D01*
G01X550430Y24335D01*
G02X549843Y25750I1412J1415D01*
G01Y26772D01*
G02X550429Y28186I1999J0D01*
G01X551143Y28900D01*
Y34853D01*
X550748Y35248D01*
X550749Y35249D01*
Y40512D01*
G01X572796D02*
Y35248D01*
X572401Y34853D01*
Y23820D01*
X573721Y22500D01*
G01X568721D02*
X570041Y23820D01*
Y34853D01*
X569646Y35248D01*
Y40512D01*
G01X1270610Y21960D02*
X1271930Y23280D01*
Y34852D01*
X1271536Y35246D01*
Y40512D01*
G01X1323559Y36200D02*
X1321939Y34580D01*
Y21188D01*
G02X1321353Y19774I-1999J0D01*
G01X1319965Y18386D01*
G02X1318551Y17800I-1414J1413D01*
G01X1296047D01*
G02X1292964Y19077I0J4360D01*
G01X1292105Y19936D01*
G02X1290828Y23019I3083J3083D01*
G01Y34852D01*
X1290433Y35247D01*
Y40512D01*
G01X1317959Y36200D02*
X1319579Y34580D01*
Y31728D01*
G02X1318993Y30314I-1999J0D01*
G01X1318765Y30086D01*
G03X1318179Y28672I1413J-1414D01*
G01Y27628D01*
G03X1318765Y26214I1999J0D01*
G01X1318993Y25986D01*
G02X1319579Y24572I-1413J-1414D01*
G01Y21736D01*
G02X1319298Y21057I-961J0D01*
G01X1318682Y20441D01*
G02X1318003Y20160I-679J680D01*
G01X1313847D01*
G02X1312433Y20746I0J1999D01*
G01X1312205Y20974D01*
G03X1310791Y21560I-1414J-1413D01*
G01X1309567D01*
G03X1308153Y20974I0J-1999D01*
G01X1307925Y20746D01*
G02X1306511Y20160I-1414J1413D01*
G01X1305347D01*
G02X1303933Y20746I0J1999D01*
G01X1303705Y20974D01*
G03X1302291Y21560I-1414J-1413D01*
G01X1300967D01*
G03X1299553Y20974I0J-1999D01*
G01X1299325Y20746D01*
G02X1297911Y20160I-1414J1413D01*
G01X1296047D01*
G02X1294633Y20746I0J1999D01*
G01X1293774Y21605D01*
G02X1293188Y23019I1413J1414D01*
G01Y34852D01*
X1293583Y35247D01*
Y40512D01*
G01X1275610Y21960D02*
X1274290Y23280D01*
Y34852D01*
X1274685Y35247D01*
Y40512D01*
G01X1393379Y20580D02*
X1394113Y19846D01*
G03X1395527Y19260I1414J1413D01*
G01X1396611D01*
G03X1398025Y19846I0J1999D01*
G01X1398193Y20014D01*
G02X1399607Y20600I1414J-1413D01*
G01X1400644D01*
G02X1401554Y20223I0J-1287D01*
G01X1401931Y19846D01*
G03X1403345Y19260I1414J1413D01*
G01X1404249D01*
G03X1405663Y19846I0J1999D01*
G01X1405831Y20014D01*
G02X1407245Y20600I1414J-1413D01*
G01X1408206D01*
G02X1409116Y20223I0J-1287D01*
G01X1409493Y19846D01*
G03X1410907Y19260I1414J1413D01*
G01X1412411D01*
G03X1413825Y19846I0J1999D01*
G01X1413993Y20014D01*
G02X1415407Y20600I1414J-1413D01*
G01X1416228D01*
G02X1417339Y20140I0J-1572D01*
G01X1417800Y19679D01*
G03X1418811Y19260I1011J1010D01*
G01X1419403D01*
G03X1420082Y19541I0J961D01*
G01X1420941Y20400D01*
G03X1421222Y21079I-680J679D01*
G01Y22793D01*
G03X1420636Y24208I-2000J1D01*
G01X1420509Y24335D01*
G02X1419922Y25750I1412J1415D01*
G01Y26772D01*
G02X1420508Y28186I1999J0D01*
G01X1421222Y28900D01*
Y34853D01*
X1420827Y35248D01*
X1420828Y35249D01*
Y40511D01*
G01X1393379Y15580D02*
X1394699Y16900D01*
X1419951D01*
G03X1421365Y17486I0J1999D01*
G01X1422996Y19117D01*
G03X1423582Y20531I-1413J1414D01*
G01Y34853D01*
X1423977Y35248D01*
Y40511D01*
G01X1443800Y22500D02*
X1442480Y23820D01*
Y34853D01*
X1442875Y35248D01*
Y40511D01*
G01X1438800Y22500D02*
X1440120Y23820D01*
Y34853D01*
X1439725Y35248D01*
Y40511D01*
G54D38*
X430591Y56653D03*
X579883Y56654D03*
X1300670D03*
X1449962Y56653D03*
G54D29*
X351654Y37400D03*
X1221732D03*
G54D47*
X641212Y132244D03*
X791764D03*
X1511291D03*
X1661843D03*
G54D48*
X660965Y101968D03*
X664114D03*
X667264D03*
X670414D03*
X673563D03*
X659390Y111850D03*
X662540D03*
X665689D03*
X668839D03*
X671988D03*
X675138D03*
X676713Y101968D03*
X679862D03*
X683012D03*
X686162D03*
X689311D03*
X692461D03*
X695610D03*
X678288Y111850D03*
X681437D03*
X684587D03*
X687736D03*
X690886D03*
X694036D03*
X697185D03*
X698760Y101968D03*
X735807D03*
X738956D03*
X742106D03*
X734232Y111850D03*
X737382D03*
X740531D03*
X743681D03*
X745256Y101968D03*
X748405D03*
X751555D03*
X754704D03*
X757854D03*
X761004D03*
X764153D03*
X767303D03*
X746830Y111850D03*
X749980D03*
X753130D03*
X756279D03*
X759429D03*
X762578D03*
X765728D03*
X770452Y101968D03*
X773602D03*
X768878Y111850D03*
X772027D03*
X1531043Y101968D03*
X1534192D03*
X1537342D03*
X1540492D03*
X1543641D03*
X1546791D03*
X1549940D03*
X1529468Y111850D03*
X1532618D03*
X1535767D03*
X1538917D03*
X1542066D03*
X1545216D03*
X1548366D03*
X1553090Y101968D03*
X1556240D03*
X1559389D03*
X1562539D03*
X1565688D03*
X1568838D03*
X1551515Y111850D03*
X1554665D03*
X1557814D03*
X1560964D03*
X1564114D03*
X1567263D03*
X1605886Y101968D03*
X1609035D03*
X1612185D03*
X1615335D03*
X1618484D03*
X1604311Y111850D03*
X1607461D03*
X1610610D03*
X1613760D03*
X1616909D03*
X1621634Y101968D03*
X1624783D03*
X1627933D03*
X1631083D03*
X1634232D03*
X1637382D03*
X1640531D03*
X1620059Y111850D03*
X1623209D03*
X1626358D03*
X1629508D03*
X1632657D03*
X1635807D03*
X1638957D03*
X1642106D03*
X1643681Y101968D03*
G54D39*
X439744Y60217D03*
X589036D03*
X1309823D03*
X1459114D03*
G54D49*
X670425Y82539D03*
X679874D03*
X689323D03*
X745268D03*
X754716D03*
X764165D03*
X1540504D03*
X1549953D03*
X1559402D03*
X1615347D03*
X1624795D03*
X1634244D03*
M02*
